G04 ================== begin FILE IDENTIFICATION RECORD ==================*
G04 Layout Name:  13919-sa.brd*
G04 Film Name:    DP_REF_L1*
G04 File Format:  Gerber RS274X*
G04 File Origin:  Cadence Allegro 16.5-S039*
G04 Origin Date:  Fri Nov 22 15:27:06 2013*
G04 *
G04 Layer:  BOARD GEOMETRY/DP_REF_L1_TBL*
G04 Layer:  BOARD GEOMETRY/DP_REF_L1_TOP*
G04 Layer:  BOARD GEOMETRY/PANEL_OUTLINE*
G04 *
G04 Offset:    (0.00 0.00)*
G04 Mirror:    No*
G04 Mode:      Positive*
G04 Rotation:  0*
G04 FullContactRelief:  No*
G04 UndefLineWidth:     6.00*
G04 ================== end FILE IDENTIFICATION RECORD ====================*
%FSLAX35Y35*MOIN*%
%IR0*IPPOS*OFA0.00000B0.00000*MIA0B0*SFA1.00000B1.00000*%
%ADD10C,.02*%
%ADD11C,.006*%
%ADD12C,.0055*%
G75*
%LPD*%
G75*
G54D10*
G01X825891Y587689D02*
X1350891D01*
G01X825891Y656989D02*
Y587689D01*
G01Y622339D02*
X1350891D01*
G01X825891Y656989D02*
X1350891D01*
G01X1000891D02*
Y587689D01*
G01X1245891Y656989D02*
Y587689D01*
G01X1350891Y656989D02*
Y587689D01*
G54D11*
G01X-14021Y-32800D02*
Y-50300D01*
G01X-19043Y-32800D02*
X-8999D01*
G01X-233Y-50300D02*
Y-32800D01*
G01Y-41258D02*
X859Y-39800D01*
X1951Y-38925D01*
X3697Y-38634D01*
X5007Y-38925D01*
X6536Y-40092D01*
X7191Y-41842D01*
Y-50300D01*
G01X20979Y-38634D02*
Y-50300D01*
G01Y-33967D02*
X20542Y-33675D01*
Y-33092D01*
X20979Y-32800D01*
X21416Y-33092D01*
Y-33675D01*
X20979Y-33967D01*
G01X35204Y-48259D02*
X36296Y-49425D01*
X37824Y-50300D01*
X39134D01*
X40444Y-49717D01*
X41317Y-48842D01*
X41754Y-47676D01*
X41536Y-45925D01*
X40662Y-45050D01*
X36732Y-43300D01*
X35859Y-41258D01*
X36296Y-39800D01*
X37169Y-38925D01*
X38479Y-38634D01*
X39789Y-38925D01*
X41099Y-39800D01*
G01X70422Y-54675D02*
X71951Y-55842D01*
X73697Y-56133D01*
X75225Y-55842D01*
X76536Y-54384D01*
X77409Y-52342D01*
Y-38634D01*
G01Y-40967D02*
X76536Y-39800D01*
X75225Y-38925D01*
X73697Y-38634D01*
X71951Y-39217D01*
X70859Y-40383D01*
X69985Y-42425D01*
X69549Y-44467D01*
X69767Y-46217D01*
X70641Y-48259D01*
X71951Y-49717D01*
X73697Y-50300D01*
X75007Y-50008D01*
X76536Y-48842D01*
X77409Y-47676D01*
G01X87704Y-42425D02*
X94691D01*
X94036Y-40383D01*
X92944Y-39217D01*
X91416Y-38634D01*
X89887Y-38925D01*
X88577Y-39800D01*
X87704Y-41842D01*
X87267Y-43592D01*
Y-45342D01*
X87704Y-47092D01*
X88796Y-48842D01*
X90106Y-50008D01*
X91634Y-50300D01*
X93162Y-49717D01*
X94691Y-47967D01*
G01X105422Y-50300D02*
Y-38634D01*
G01Y-40967D02*
X106514Y-39800D01*
X107606Y-38925D01*
X109134Y-38634D01*
X110225Y-38925D01*
X111536Y-39800D01*
G01X122049Y-50300D02*
Y-32800D01*
G01Y-41550D02*
X123141Y-39800D01*
X124451Y-38925D01*
X125761Y-38634D01*
X127725Y-39217D01*
X129036Y-40383D01*
X129909Y-42425D01*
Y-44758D01*
X129472Y-47092D01*
X128599Y-48842D01*
X127071Y-50008D01*
X125761Y-50300D01*
X124451Y-50008D01*
X123141Y-49134D01*
X122049Y-47676D01*
G01X140204Y-42425D02*
X147191D01*
X146536Y-40383D01*
X145444Y-39217D01*
X143916Y-38634D01*
X142387Y-38925D01*
X141077Y-39800D01*
X140204Y-41842D01*
X139767Y-43592D01*
Y-45342D01*
X140204Y-47092D01*
X141296Y-48842D01*
X142606Y-50008D01*
X144134Y-50300D01*
X145662Y-49717D01*
X147191Y-47967D01*
G01X157922Y-50300D02*
Y-38634D01*
G01Y-40967D02*
X159014Y-39800D01*
X160106Y-38925D01*
X161634Y-38634D01*
X162725Y-38925D01*
X164036Y-39800D01*
G01X195979Y-38634D02*
Y-50300D01*
G01Y-33967D02*
X195542Y-33675D01*
Y-33092D01*
X195979Y-32800D01*
X196416Y-33092D01*
Y-33675D01*
X195979Y-33967D01*
G01X210204Y-48259D02*
X211296Y-49425D01*
X212824Y-50300D01*
X214134D01*
X215444Y-49717D01*
X216317Y-48842D01*
X216754Y-47676D01*
X216536Y-45925D01*
X215662Y-45050D01*
X211732Y-43300D01*
X210859Y-41258D01*
X211296Y-39800D01*
X212169Y-38925D01*
X213479Y-38634D01*
X214789Y-38925D01*
X216099Y-39800D01*
G01X244985Y-54675D02*
X246514Y-55842D01*
X247824Y-56133D01*
X249571Y-55550D01*
X250881Y-54092D01*
X251536Y-51466D01*
Y-38634D01*
G01Y-33967D02*
X251099Y-33675D01*
Y-33092D01*
X251536Y-32800D01*
X251972Y-33092D01*
Y-33675D01*
X251536Y-33967D01*
G01X262267Y-38634D02*
Y-46800D01*
X263141Y-48842D01*
X264451Y-50008D01*
X265979Y-50300D01*
X267507Y-50008D01*
X268817Y-48842D01*
X269691Y-46800D01*
G01Y-50300D02*
Y-38634D01*
G01X280204Y-48259D02*
X281296Y-49425D01*
X282824Y-50300D01*
X284134D01*
X285444Y-49717D01*
X286317Y-48842D01*
X286754Y-47676D01*
X286536Y-45925D01*
X285662Y-45050D01*
X281732Y-43300D01*
X280859Y-41258D01*
X281296Y-39800D01*
X282169Y-38925D01*
X283479Y-38634D01*
X284789Y-38925D01*
X286099Y-39800D01*
G01X300979Y-32800D02*
Y-50300D01*
G01X297922Y-38634D02*
X304036D01*
G01X334669Y-50300D02*
Y-35425D01*
X335106Y-33967D01*
X335979Y-33092D01*
X337289Y-32800D01*
X338599Y-33383D01*
X339254Y-34842D01*
G01X336634Y-39800D02*
X332267D01*
G01X353479Y-50300D02*
X352169Y-50008D01*
X350859Y-48842D01*
X349985Y-46800D01*
X349549Y-44467D01*
X349985Y-42133D01*
X350859Y-40092D01*
X352169Y-38925D01*
X353479Y-38634D01*
X354789Y-38925D01*
X356099Y-40092D01*
X356972Y-42133D01*
X357191Y-44467D01*
X356972Y-46800D01*
X356099Y-48842D01*
X354789Y-50008D01*
X353479Y-50300D01*
G01X367922D02*
Y-38634D01*
G01Y-40967D02*
X369014Y-39800D01*
X370106Y-38925D01*
X371634Y-38634D01*
X372725Y-38925D01*
X374036Y-39800D01*
G01X401394Y-55550D02*
X402704Y-56133D01*
X404451Y-55550D01*
X405542Y-54384D01*
X406416Y-52925D01*
X407725Y-48259D01*
X410564Y-38634D01*
G01X403577D02*
X407725Y-48259D01*
G01X423479Y-50300D02*
X422169Y-50008D01*
X420859Y-48842D01*
X419985Y-46800D01*
X419549Y-44467D01*
X419985Y-42133D01*
X420859Y-40092D01*
X422169Y-38925D01*
X423479Y-38634D01*
X424789Y-38925D01*
X426099Y-40092D01*
X426972Y-42133D01*
X427191Y-44467D01*
X426972Y-46800D01*
X426099Y-48842D01*
X424789Y-50008D01*
X423479Y-50300D01*
G01X437267Y-38634D02*
Y-46800D01*
X438141Y-48842D01*
X439451Y-50008D01*
X440979Y-50300D01*
X442507Y-50008D01*
X443817Y-48842D01*
X444691Y-46800D01*
G01Y-50300D02*
Y-38634D01*
G01X455422Y-50300D02*
Y-38634D01*
G01Y-40967D02*
X456514Y-39800D01*
X457606Y-38925D01*
X459134Y-38634D01*
X460225Y-38925D01*
X461536Y-39800D01*
G01X490422Y-50300D02*
Y-38634D01*
G01Y-40967D02*
X491514Y-39800D01*
X492606Y-38925D01*
X494134Y-38634D01*
X495225Y-38925D01*
X496536Y-39800D01*
G01X507704Y-42425D02*
X514691D01*
X514036Y-40383D01*
X512944Y-39217D01*
X511416Y-38634D01*
X509887Y-38925D01*
X508577Y-39800D01*
X507704Y-41842D01*
X507267Y-43592D01*
Y-45342D01*
X507704Y-47092D01*
X508796Y-48842D01*
X510106Y-50008D01*
X511634Y-50300D01*
X513162Y-49717D01*
X514691Y-47967D01*
G01X527169Y-50300D02*
Y-35425D01*
X527606Y-33967D01*
X528479Y-33092D01*
X529789Y-32800D01*
X531099Y-33383D01*
X531754Y-34842D01*
G01X529134Y-39800D02*
X524767D01*
G01X542704Y-42425D02*
X549691D01*
X549036Y-40383D01*
X547944Y-39217D01*
X546416Y-38634D01*
X544887Y-38925D01*
X543577Y-39800D01*
X542704Y-41842D01*
X542267Y-43592D01*
Y-45342D01*
X542704Y-47092D01*
X543796Y-48842D01*
X545106Y-50008D01*
X546634Y-50300D01*
X548162Y-49717D01*
X549691Y-47967D01*
G01X560422Y-50300D02*
Y-38634D01*
G01Y-40967D02*
X561514Y-39800D01*
X562606Y-38925D01*
X564134Y-38634D01*
X565225Y-38925D01*
X566536Y-39800D01*
G01X577704Y-42425D02*
X584691D01*
X584036Y-40383D01*
X582944Y-39217D01*
X581416Y-38634D01*
X579887Y-38925D01*
X578577Y-39800D01*
X577704Y-41842D01*
X577267Y-43592D01*
Y-45342D01*
X577704Y-47092D01*
X578796Y-48842D01*
X580106Y-50008D01*
X581634Y-50300D01*
X583162Y-49717D01*
X584691Y-47967D01*
G01X594767Y-50300D02*
Y-38634D01*
G01Y-41550D02*
X595641Y-40092D01*
X596951Y-38925D01*
X598697Y-38634D01*
X600225Y-38925D01*
X601536Y-40092D01*
X602191Y-42133D01*
Y-50300D01*
G01X619472Y-40092D02*
X617944Y-38925D01*
X616634Y-38634D01*
X614887Y-39217D01*
X613577Y-40383D01*
X612704Y-42425D01*
X612485Y-44467D01*
X612704Y-46509D01*
X613577Y-48259D01*
X614887Y-49717D01*
X616634Y-50300D01*
X618162Y-49717D01*
X619472Y-48550D01*
G01X630204Y-42425D02*
X637191D01*
X636536Y-40383D01*
X635444Y-39217D01*
X633916Y-38634D01*
X632387Y-38925D01*
X631077Y-39800D01*
X630204Y-41842D01*
X629767Y-43592D01*
Y-45342D01*
X630204Y-47092D01*
X631296Y-48842D01*
X632606Y-50008D01*
X634134Y-50300D01*
X635662Y-49717D01*
X637191Y-47967D01*
G01X668479Y-32800D02*
Y-50300D01*
G01X665422Y-38634D02*
X671536D01*
G01X685979Y-50300D02*
X684669Y-50008D01*
X683359Y-48842D01*
X682485Y-46800D01*
X682049Y-44467D01*
X682485Y-42133D01*
X683359Y-40092D01*
X684669Y-38925D01*
X685979Y-38634D01*
X687289Y-38925D01*
X688599Y-40092D01*
X689472Y-42133D01*
X689691Y-44467D01*
X689472Y-46800D01*
X688599Y-48842D01*
X687289Y-50008D01*
X685979Y-50300D01*
G01X719669D02*
Y-35425D01*
X720106Y-33967D01*
X720979Y-33092D01*
X722289Y-32800D01*
X723599Y-33383D01*
X724254Y-34842D01*
G01X721634Y-39800D02*
X717267D01*
G01X738479Y-38634D02*
Y-50300D01*
G01Y-33967D02*
X738042Y-33675D01*
Y-33092D01*
X738479Y-32800D01*
X738916Y-33092D01*
Y-33675D01*
X738479Y-33967D01*
G01X752267Y-50300D02*
Y-38634D01*
G01Y-41550D02*
X753141Y-40092D01*
X754451Y-38925D01*
X756197Y-38634D01*
X757725Y-38925D01*
X759036Y-40092D01*
X759691Y-42133D01*
Y-50300D01*
G01X777409Y-32800D02*
Y-50300D01*
G01Y-47676D02*
X776536Y-49134D01*
X775225Y-50008D01*
X773697Y-50300D01*
X771951Y-49717D01*
X770641Y-48259D01*
X769767Y-46509D01*
X769549Y-44467D01*
X769767Y-42425D01*
X770641Y-40675D01*
X771951Y-39217D01*
X773697Y-38634D01*
X775225Y-38925D01*
X776317Y-39509D01*
X777409Y-40675D01*
G01X808479Y-32800D02*
Y-50300D01*
G01X805422Y-38634D02*
X811536D01*
G01X822267Y-50300D02*
Y-32800D01*
G01Y-41258D02*
X823359Y-39800D01*
X824451Y-38925D01*
X826197Y-38634D01*
X827507Y-38925D01*
X829036Y-40092D01*
X829691Y-41842D01*
Y-50300D01*
G01X840204Y-42425D02*
X847191D01*
X846536Y-40383D01*
X845444Y-39217D01*
X843916Y-38634D01*
X842387Y-38925D01*
X841077Y-39800D01*
X840204Y-41842D01*
X839767Y-43592D01*
Y-45342D01*
X840204Y-47092D01*
X841296Y-48842D01*
X842606Y-50008D01*
X844134Y-50300D01*
X845662Y-49717D01*
X847191Y-47967D01*
G01X873676Y-50300D02*
Y-32800D01*
X878042D01*
X879789Y-33675D01*
X881099Y-34842D01*
X882191Y-36591D01*
X883064Y-38634D01*
X883282Y-41550D01*
X883064Y-44467D01*
X882191Y-46509D01*
X881099Y-48259D01*
X879789Y-49425D01*
X878042Y-50300D01*
X873676D01*
G01X891612D02*
Y-32800D01*
X896852D01*
X898599Y-33675D01*
X899909Y-35717D01*
X900346Y-38050D01*
X899909Y-40383D01*
X898817Y-42133D01*
X896852Y-43009D01*
X891612D01*
G01X930979Y-38634D02*
Y-50300D01*
G01Y-33967D02*
X930542Y-33675D01*
Y-33092D01*
X930979Y-32800D01*
X931416Y-33092D01*
Y-33675D01*
X930979Y-33967D01*
G01X941929Y-50300D02*
Y-38634D01*
G01Y-41842D02*
X942584Y-40383D01*
X943676Y-39217D01*
X945204Y-38634D01*
X946732Y-39217D01*
X947824Y-40383D01*
X948479Y-41842D01*
Y-50300D01*
G01Y-41842D02*
X949134Y-40383D01*
X950225Y-39217D01*
X951754Y-38634D01*
X953282Y-39217D01*
X954374Y-40383D01*
X955029Y-42133D01*
Y-50300D01*
G01X962049Y-56133D02*
Y-38634D01*
G01Y-41258D02*
X963141Y-39800D01*
X964232Y-38925D01*
X965979Y-38634D01*
X967507Y-38925D01*
X969036Y-40383D01*
X969691Y-42425D01*
X969909Y-44467D01*
X969691Y-46509D01*
X969036Y-48550D01*
X967725Y-49717D01*
X965979Y-50300D01*
X964451Y-50008D01*
X962922Y-49134D01*
X962049Y-47967D01*
G01X980204Y-42425D02*
X987191D01*
X986536Y-40383D01*
X985444Y-39217D01*
X983916Y-38634D01*
X982387Y-38925D01*
X981077Y-39800D01*
X980204Y-41842D01*
X979767Y-43592D01*
Y-45342D01*
X980204Y-47092D01*
X981296Y-48842D01*
X982606Y-50008D01*
X984134Y-50300D01*
X985662Y-49717D01*
X987191Y-47967D01*
G01X1004909Y-32800D02*
Y-50300D01*
G01Y-47676D02*
X1004036Y-49134D01*
X1002725Y-50008D01*
X1001197Y-50300D01*
X999451Y-49717D01*
X998141Y-48259D01*
X997267Y-46509D01*
X997049Y-44467D01*
X997267Y-42425D01*
X998141Y-40675D01*
X999451Y-39217D01*
X1001197Y-38634D01*
X1002725Y-38925D01*
X1003817Y-39509D01*
X1004909Y-40675D01*
G01X1022409Y-50300D02*
Y-38634D01*
G01Y-40675D02*
X1021536Y-39509D01*
X1020225Y-38925D01*
X1018697Y-38634D01*
X1017169Y-39217D01*
X1015859Y-40383D01*
X1014985Y-42133D01*
X1014549Y-44467D01*
X1014985Y-46800D01*
X1015859Y-48550D01*
X1017169Y-49717D01*
X1018697Y-50300D01*
X1020225Y-50008D01*
X1021536Y-49134D01*
X1022409Y-47967D01*
G01X1032267Y-50300D02*
Y-38634D01*
G01Y-41550D02*
X1033141Y-40092D01*
X1034451Y-38925D01*
X1036197Y-38634D01*
X1037725Y-38925D01*
X1039036Y-40092D01*
X1039691Y-42133D01*
Y-50300D01*
G01X1056972Y-40092D02*
X1055444Y-38925D01*
X1054134Y-38634D01*
X1052387Y-39217D01*
X1051077Y-40383D01*
X1050204Y-42425D01*
X1049985Y-44467D01*
X1050204Y-46509D01*
X1051077Y-48259D01*
X1052387Y-49717D01*
X1054134Y-50300D01*
X1055662Y-49717D01*
X1056972Y-48550D01*
G01X1067704Y-42425D02*
X1074691D01*
X1074036Y-40383D01*
X1072944Y-39217D01*
X1071416Y-38634D01*
X1069887Y-38925D01*
X1068577Y-39800D01*
X1067704Y-41842D01*
X1067267Y-43592D01*
Y-45342D01*
X1067704Y-47092D01*
X1068796Y-48842D01*
X1070106Y-50008D01*
X1071634Y-50300D01*
X1073162Y-49717D01*
X1074691Y-47967D01*
G01X1105979Y-32800D02*
Y-50300D01*
G01X1102922Y-38634D02*
X1109036D01*
G01X1120422Y-50300D02*
Y-38634D01*
G01Y-40967D02*
X1121514Y-39800D01*
X1122606Y-38925D01*
X1124134Y-38634D01*
X1125225Y-38925D01*
X1126536Y-39800D01*
G01X1144909Y-50300D02*
Y-38634D01*
G01Y-40675D02*
X1144036Y-39509D01*
X1142725Y-38925D01*
X1141197Y-38634D01*
X1139669Y-39217D01*
X1138359Y-40383D01*
X1137485Y-42133D01*
X1137049Y-44467D01*
X1137485Y-46800D01*
X1138359Y-48550D01*
X1139669Y-49717D01*
X1141197Y-50300D01*
X1142725Y-50008D01*
X1144036Y-49134D01*
X1144909Y-47967D01*
G01X1161972Y-40092D02*
X1160444Y-38925D01*
X1159134Y-38634D01*
X1157387Y-39217D01*
X1156077Y-40383D01*
X1155204Y-42425D01*
X1154985Y-44467D01*
X1155204Y-46509D01*
X1156077Y-48259D01*
X1157387Y-49717D01*
X1159134Y-50300D01*
X1160662Y-49717D01*
X1161972Y-48550D01*
G01X1172704Y-42425D02*
X1179691D01*
X1179036Y-40383D01*
X1177944Y-39217D01*
X1176416Y-38634D01*
X1174887Y-38925D01*
X1173577Y-39800D01*
X1172704Y-41842D01*
X1172267Y-43592D01*
Y-45342D01*
X1172704Y-47092D01*
X1173796Y-48842D01*
X1175106Y-50008D01*
X1176634Y-50300D01*
X1178162Y-49717D01*
X1179691Y-47967D01*
G01X1190204Y-48259D02*
X1191296Y-49425D01*
X1192824Y-50300D01*
X1194134D01*
X1195444Y-49717D01*
X1196317Y-48842D01*
X1196754Y-47676D01*
X1196536Y-45925D01*
X1195662Y-45050D01*
X1191732Y-43300D01*
X1190859Y-41258D01*
X1191296Y-39800D01*
X1192169Y-38925D01*
X1193479Y-38634D01*
X1194789Y-38925D01*
X1196099Y-39800D01*
G01X1228479Y-38634D02*
Y-50300D01*
G01Y-33967D02*
X1228042Y-33675D01*
Y-33092D01*
X1228479Y-32800D01*
X1228916Y-33092D01*
Y-33675D01*
X1228479Y-33967D01*
G01X1242267Y-50300D02*
Y-38634D01*
G01Y-41550D02*
X1243141Y-40092D01*
X1244451Y-38925D01*
X1246197Y-38634D01*
X1247725Y-38925D01*
X1249036Y-40092D01*
X1249691Y-42133D01*
Y-50300D01*
G01X1280979D02*
Y-32800D01*
G01X1302409Y-50300D02*
Y-38634D01*
G01Y-40675D02*
X1301536Y-39509D01*
X1300225Y-38925D01*
X1298697Y-38634D01*
X1297169Y-39217D01*
X1295859Y-40383D01*
X1294985Y-42133D01*
X1294549Y-44467D01*
X1294985Y-46800D01*
X1295859Y-48550D01*
X1297169Y-49717D01*
X1298697Y-50300D01*
X1300225Y-50008D01*
X1301536Y-49134D01*
X1302409Y-47967D01*
G01X1311394Y-55550D02*
X1312704Y-56133D01*
X1314451Y-55550D01*
X1315542Y-54384D01*
X1316416Y-52925D01*
X1317725Y-48259D01*
X1320564Y-38634D01*
G01X1313577D02*
X1317725Y-48259D01*
G01X1330204Y-42425D02*
X1337191D01*
X1336536Y-40383D01*
X1335444Y-39217D01*
X1333916Y-38634D01*
X1332387Y-38925D01*
X1331077Y-39800D01*
X1330204Y-41842D01*
X1329767Y-43592D01*
Y-45342D01*
X1330204Y-47092D01*
X1331296Y-48842D01*
X1332606Y-50008D01*
X1334134Y-50300D01*
X1335662Y-49717D01*
X1337191Y-47967D01*
G01X1347922Y-50300D02*
Y-38634D01*
G01Y-40967D02*
X1349014Y-39800D01*
X1350106Y-38925D01*
X1351634Y-38634D01*
X1352725Y-38925D01*
X1354036Y-39800D01*
G01X1381612Y-32800D02*
Y-50300D01*
X1390346D01*
G01X1403479D02*
Y-32800D01*
X1400859Y-36300D01*
G01Y-50300D02*
X1406099D01*
G01X1420979Y-50883D02*
X1420542Y-50592D01*
Y-50008D01*
X1420979Y-49717D01*
X1421416Y-50008D01*
Y-50592D01*
X1420979Y-50883D01*
G01X827638Y666739D02*
Y684239D01*
X832004D01*
X833751Y683364D01*
X835061Y682197D01*
X836153Y680448D01*
X837026Y678405D01*
X837244Y675489D01*
X837026Y672572D01*
X836153Y670530D01*
X835061Y668780D01*
X833751Y667614D01*
X832004Y666739D01*
X827638D01*
G01X845574D02*
Y684239D01*
X850814D01*
X852561Y683364D01*
X853871Y681322D01*
X854308Y678989D01*
X853871Y676656D01*
X852779Y674906D01*
X850814Y674030D01*
X845574D01*
G01X882321Y684239D02*
X887561D01*
G01X884941D02*
Y666739D01*
G01X882321D02*
X887561D01*
G01X896764D02*
Y684239D01*
X902441Y669656D01*
X908118Y684239D01*
Y666739D01*
G01X915574D02*
Y684239D01*
X920814D01*
X922561Y683364D01*
X923871Y681322D01*
X924308Y678989D01*
X923871Y676656D01*
X922779Y674906D01*
X920814Y674030D01*
X915574D01*
G01X941808Y666739D02*
X933074D01*
Y684239D01*
X941808D01*
G01X938314Y675781D02*
X933074D01*
G01X950138Y666739D02*
Y684239D01*
X954504D01*
X956251Y683364D01*
X957561Y682197D01*
X958653Y680448D01*
X959526Y678405D01*
X959744Y675489D01*
X959526Y672572D01*
X958653Y670530D01*
X957561Y668780D01*
X956251Y667614D01*
X954504Y666739D01*
X950138D01*
G01X966982D02*
X972441Y684239D01*
X977900Y666739D01*
G01X975934Y672864D02*
X968947D01*
G01X984919Y666739D02*
Y684239D01*
X994963Y666739D01*
Y684239D01*
G01X1012244Y682780D02*
X1010934Y683656D01*
X1009406Y684239D01*
X1007659D01*
X1005694Y683364D01*
X1004166Y681906D01*
X1003074Y680155D01*
X1002201Y677239D01*
X1001982Y674614D01*
X1002419Y671989D01*
X1003074Y670239D01*
X1004384Y668489D01*
X1005913Y667322D01*
X1007441Y666739D01*
X1008969D01*
X1010498Y667322D01*
X1011808Y668197D01*
X1012900Y669363D01*
G01X1029308Y666739D02*
X1020574D01*
Y684239D01*
X1029308D01*
G01X1025814Y675781D02*
X1020574D01*
G01X1059941Y684239D02*
Y666739D01*
G01X1054919Y684239D02*
X1064963D01*
G01X1071982Y666739D02*
X1077441Y684239D01*
X1082900Y666739D01*
G01X1080934Y672864D02*
X1073947D01*
G01X1096687Y676072D02*
X1097561Y676947D01*
X1098216Y678405D01*
X1098653Y680448D01*
X1098216Y682197D01*
X1097343Y683364D01*
X1095814Y684239D01*
X1089919D01*
Y666739D01*
X1097124D01*
X1098653Y667905D01*
X1099526Y669656D01*
X1099963Y671697D01*
X1099526Y673739D01*
X1098216Y675489D01*
X1096687Y676072D01*
X1089919D01*
G01X1108074Y684239D02*
Y666739D01*
X1116808D01*
G01X1134308D02*
X1125574D01*
Y684239D01*
X1134308D01*
G01X1130814Y675781D02*
X1125574D01*
G01X1147441Y666156D02*
X1147004Y666447D01*
Y667031D01*
X1147441Y667322D01*
X1147878Y667031D01*
Y666447D01*
X1147441Y666156D01*
G01Y674030D02*
X1147004Y674322D01*
Y674906D01*
X1147441Y675197D01*
X1147878Y674906D01*
Y674322D01*
X1147441Y674030D01*
G01X1178074Y684239D02*
Y666739D01*
X1186808D01*
G01X1199941D02*
Y684239D01*
X1197321Y680739D01*
G01Y666739D02*
X1202561D01*
G01X849521Y649589D02*
X854761D01*
G01X852141D02*
Y632089D01*
G01X849521D02*
X854761D01*
G01X863964D02*
Y649589D01*
X869641Y635006D01*
X875318Y649589D01*
Y632089D01*
G01X882774D02*
Y649589D01*
X888014D01*
X889761Y648714D01*
X891071Y646672D01*
X891508Y644339D01*
X891071Y642006D01*
X889979Y640256D01*
X888014Y639380D01*
X882774D01*
G01X903549Y626256D02*
X901366Y629172D01*
X900274Y632089D01*
Y643755D01*
X901366Y646672D01*
X903549Y649589D01*
G01X922141Y632089D02*
X920394Y632381D01*
X918866Y633547D01*
X917556Y635297D01*
X916682Y637339D01*
X916246Y639672D01*
Y642006D01*
X916682Y644339D01*
X917556Y646381D01*
X918866Y648130D01*
X920394Y649297D01*
X922141Y649589D01*
X923887Y649297D01*
X925416Y648130D01*
X926726Y646381D01*
X927600Y644339D01*
X928036Y642006D01*
Y639672D01*
X927600Y637339D01*
X926726Y635297D01*
X925416Y633547D01*
X923887Y632381D01*
X922141Y632089D01*
G01X935929D02*
Y649589D01*
G01Y641131D02*
X937021Y642589D01*
X938113Y643464D01*
X939859Y643755D01*
X941169Y643464D01*
X942698Y642297D01*
X943353Y640547D01*
Y632089D01*
G01X950591D02*
Y643755D01*
G01Y640547D02*
X951246Y642006D01*
X952338Y643172D01*
X953866Y643755D01*
X955394Y643172D01*
X956486Y642006D01*
X957141Y640547D01*
Y632089D01*
G01Y640547D02*
X957796Y642006D01*
X958887Y643172D01*
X960416Y643755D01*
X961944Y643172D01*
X963036Y642006D01*
X963691Y640256D01*
Y632089D01*
G01X975733Y626256D02*
X977916Y629172D01*
X979008Y632089D01*
Y643755D01*
X977916Y646672D01*
X975733Y649589D01*
G01X887141Y597439D02*
X888669Y597731D01*
X890416Y598605D01*
X891508Y600063D01*
X891944Y602106D01*
X891508Y604147D01*
X890198Y605897D01*
X888233Y606772D01*
X886049D01*
X884739Y607356D01*
X883647Y608814D01*
X883211Y610855D01*
X883866Y612897D01*
X885394Y614356D01*
X887141Y614939D01*
X888887Y614356D01*
X890416Y612897D01*
X891071Y610855D01*
X890634Y608814D01*
X889543Y607356D01*
X888233Y606772D01*
X886049D01*
X884084Y605897D01*
X882774Y604147D01*
X882338Y602106D01*
X882774Y600063D01*
X883866Y598605D01*
X885613Y597731D01*
X887141Y597439D01*
G01X899838Y600063D02*
X901147Y598605D01*
X902676Y597731D01*
X904641Y597439D01*
X906606Y598022D01*
X908134Y599189D01*
X909226Y601230D01*
X909444Y603564D01*
X909008Y605897D01*
X907916Y607356D01*
X906387Y608522D01*
X904859Y608814D01*
X903331Y608522D01*
X901366Y607356D01*
X902021Y614939D01*
X907916D01*
G01X922141Y596856D02*
X921704Y597147D01*
Y597731D01*
X922141Y598022D01*
X922578Y597731D01*
Y597147D01*
X922141Y596856D01*
G01X939641Y614939D02*
X937894Y614356D01*
X936584Y612897D01*
X935711Y611148D01*
X935056Y608814D01*
X934838Y606189D01*
X935056Y603564D01*
X935711Y601230D01*
X936584Y599480D01*
X937894Y598022D01*
X939641Y597439D01*
X941387Y598022D01*
X942698Y599480D01*
X943571Y601230D01*
X944226Y603564D01*
X944444Y606189D01*
X944226Y608814D01*
X943571Y611148D01*
X942698Y612897D01*
X941387Y614356D01*
X939641Y614939D01*
G01X1029341Y649589D02*
X1032397Y632089D01*
X1035891Y649589D01*
X1039384Y632089D01*
X1042441Y649589D01*
G01X1050771D02*
X1056011D01*
G01X1053391D02*
Y632089D01*
G01X1050771D02*
X1056011D01*
G01X1066088D02*
Y649589D01*
X1070454D01*
X1072201Y648714D01*
X1073511Y647547D01*
X1074603Y645798D01*
X1075476Y643755D01*
X1075694Y640839D01*
X1075476Y637922D01*
X1074603Y635880D01*
X1073511Y634130D01*
X1072201Y632964D01*
X1070454Y632089D01*
X1066088D01*
G01X1088391Y649589D02*
Y632089D01*
G01X1083369Y649589D02*
X1093413D01*
G01X1101306Y632089D02*
Y649589D01*
G01X1110476D02*
Y632089D01*
G01Y640839D02*
X1101306D01*
G01X1122299Y626256D02*
X1120116Y629172D01*
X1119024Y632089D01*
Y643755D01*
X1120116Y646672D01*
X1122299Y649589D01*
G01X1134341Y632089D02*
Y643755D01*
G01Y640547D02*
X1134996Y642006D01*
X1136088Y643172D01*
X1137616Y643755D01*
X1139144Y643172D01*
X1140236Y642006D01*
X1140891Y640547D01*
Y632089D01*
G01Y640547D02*
X1141546Y642006D01*
X1142637Y643172D01*
X1144166Y643755D01*
X1145694Y643172D01*
X1146786Y642006D01*
X1147441Y640256D01*
Y632089D01*
G01X1158391Y643755D02*
Y632089D01*
G01Y648422D02*
X1157954Y648714D01*
Y649297D01*
X1158391Y649589D01*
X1158828Y649297D01*
Y648714D01*
X1158391Y648422D01*
G01X1175891Y632089D02*
Y649589D01*
G01X1190116Y634130D02*
X1191208Y632964D01*
X1192736Y632089D01*
X1194046D01*
X1195356Y632672D01*
X1196229Y633547D01*
X1196666Y634713D01*
X1196448Y636464D01*
X1195574Y637339D01*
X1191644Y639089D01*
X1190771Y641131D01*
X1191208Y642589D01*
X1192081Y643464D01*
X1193391Y643755D01*
X1194701Y643464D01*
X1196011Y642589D01*
G01X1211983Y626256D02*
X1214166Y629172D01*
X1215258Y632089D01*
Y643755D01*
X1214166Y646672D01*
X1211983Y649589D01*
G01X1066088Y600063D02*
X1067397Y598605D01*
X1068926Y597731D01*
X1070891Y597439D01*
X1072856Y598022D01*
X1074384Y599189D01*
X1075476Y601230D01*
X1075694Y603564D01*
X1075258Y605897D01*
X1074166Y607356D01*
X1072637Y608522D01*
X1071109Y608814D01*
X1069581Y608522D01*
X1067616Y607356D01*
X1068271Y614939D01*
X1074166D01*
G01X1088391Y596856D02*
X1087954Y597147D01*
Y597731D01*
X1088391Y598022D01*
X1088828Y597731D01*
Y597147D01*
X1088391Y596856D01*
G01X1101088Y600063D02*
X1102397Y598605D01*
X1103926Y597731D01*
X1105891Y597439D01*
X1107856Y598022D01*
X1109384Y599189D01*
X1110476Y601230D01*
X1110694Y603564D01*
X1110258Y605897D01*
X1109166Y607356D01*
X1107637Y608522D01*
X1106109Y608814D01*
X1104581Y608522D01*
X1102616Y607356D01*
X1103271Y614939D01*
X1109166D01*
G01X1119461Y596856D02*
X1127321Y614939D01*
G01X1140891Y597439D02*
X1142419Y597731D01*
X1144166Y598605D01*
X1145258Y600063D01*
X1145694Y602106D01*
X1145258Y604147D01*
X1143948Y605897D01*
X1141983Y606772D01*
X1139799D01*
X1138489Y607356D01*
X1137397Y608814D01*
X1136961Y610855D01*
X1137616Y612897D01*
X1139144Y614356D01*
X1140891Y614939D01*
X1142637Y614356D01*
X1144166Y612897D01*
X1144821Y610855D01*
X1144384Y608814D01*
X1143293Y607356D01*
X1141983Y606772D01*
X1139799D01*
X1137834Y605897D01*
X1136524Y604147D01*
X1136088Y602106D01*
X1136524Y600063D01*
X1137616Y598605D01*
X1139363Y597731D01*
X1140891Y597439D01*
G01X1158391Y596856D02*
X1157954Y597147D01*
Y597731D01*
X1158391Y598022D01*
X1158828Y597731D01*
Y597147D01*
X1158391Y596856D01*
G01X1175891Y614939D02*
X1174144Y614356D01*
X1172834Y612897D01*
X1171961Y611148D01*
X1171306Y608814D01*
X1171088Y606189D01*
X1171306Y603564D01*
X1171961Y601230D01*
X1172834Y599480D01*
X1174144Y598022D01*
X1175891Y597439D01*
X1177637Y598022D01*
X1178948Y599480D01*
X1179821Y601230D01*
X1180476Y603564D01*
X1180694Y606189D01*
X1180476Y608814D01*
X1179821Y611148D01*
X1178948Y612897D01*
X1177637Y614356D01*
X1175891Y614939D01*
G01X1272141Y649589D02*
Y632089D01*
G01X1267119Y649589D02*
X1277163D01*
G01X1289641Y632089D02*
Y639964D01*
X1285274Y649589D01*
G01X1294008D02*
X1289641Y639964D01*
G01X1302774Y632089D02*
Y649589D01*
X1308014D01*
X1309761Y648714D01*
X1311071Y646672D01*
X1311508Y644339D01*
X1311071Y642006D01*
X1309979Y640256D01*
X1308014Y639380D01*
X1302774D01*
G01X1329008Y632089D02*
X1320274D01*
Y649589D01*
X1329008D01*
G01X1325514Y641131D02*
X1320274D01*
G01X1284838Y597439D02*
Y614939D01*
X1289204D01*
X1290951Y614064D01*
X1292261Y612897D01*
X1293353Y611148D01*
X1294226Y609105D01*
X1294444Y606189D01*
X1294226Y603272D01*
X1293353Y601230D01*
X1292261Y599480D01*
X1290951Y598314D01*
X1289204Y597439D01*
X1284838D01*
G01X1302774D02*
Y614939D01*
X1308014D01*
X1309761Y614064D01*
X1311071Y612022D01*
X1311508Y609689D01*
X1311071Y607356D01*
X1309979Y605606D01*
X1308014Y604730D01*
X1302774D01*
G01X1477441Y574455D02*
Y562789D01*
G01Y579122D02*
X1477004Y579414D01*
Y579997D01*
X1477441Y580289D01*
X1477878Y579997D01*
Y579414D01*
X1477441Y579122D01*
G01X1491229Y562789D02*
Y574455D01*
G01Y571539D02*
X1492103Y572997D01*
X1493413Y574164D01*
X1495159Y574455D01*
X1496687Y574164D01*
X1497998Y572997D01*
X1498653Y570956D01*
Y562789D01*
G01X1509166Y564830D02*
X1510258Y563664D01*
X1511786Y562789D01*
X1513096D01*
X1514406Y563372D01*
X1515279Y564247D01*
X1515716Y565413D01*
X1515498Y567164D01*
X1514624Y568039D01*
X1510694Y569789D01*
X1509821Y571831D01*
X1510258Y573289D01*
X1511131Y574164D01*
X1512441Y574455D01*
X1513751Y574164D01*
X1515061Y573289D01*
G01X1529941Y574455D02*
Y562789D01*
G01Y579122D02*
X1529504Y579414D01*
Y579997D01*
X1529941Y580289D01*
X1530378Y579997D01*
Y579414D01*
X1529941Y579122D01*
G01X1551371Y580289D02*
Y562789D01*
G01Y565413D02*
X1550498Y563955D01*
X1549187Y563081D01*
X1547659Y562789D01*
X1545913Y563372D01*
X1544603Y564830D01*
X1543729Y566580D01*
X1543511Y568622D01*
X1543729Y570664D01*
X1544603Y572414D01*
X1545913Y573872D01*
X1547659Y574455D01*
X1549187Y574164D01*
X1550279Y573580D01*
X1551371Y572414D01*
G01X1561666Y570664D02*
X1568653D01*
X1567998Y572706D01*
X1566906Y573872D01*
X1565378Y574455D01*
X1563849Y574164D01*
X1562539Y573289D01*
X1561666Y571247D01*
X1561229Y569497D01*
Y567747D01*
X1561666Y565997D01*
X1562758Y564247D01*
X1564068Y563081D01*
X1565596Y562789D01*
X1567124Y563372D01*
X1568653Y565122D01*
G01X1596011Y562789D02*
Y580289D01*
G01Y571539D02*
X1597103Y573289D01*
X1598413Y574164D01*
X1599723Y574455D01*
X1601687Y573872D01*
X1602998Y572706D01*
X1603871Y570664D01*
Y568331D01*
X1603434Y565997D01*
X1602561Y564247D01*
X1601033Y563081D01*
X1599723Y562789D01*
X1598413Y563081D01*
X1597103Y563955D01*
X1596011Y565413D01*
G01X1617441Y562789D02*
X1616131Y563081D01*
X1614821Y564247D01*
X1613947Y566289D01*
X1613511Y568622D01*
X1613947Y570956D01*
X1614821Y572997D01*
X1616131Y574164D01*
X1617441Y574455D01*
X1618751Y574164D01*
X1620061Y572997D01*
X1620934Y570956D01*
X1621153Y568622D01*
X1620934Y566289D01*
X1620061Y564247D01*
X1618751Y563081D01*
X1617441Y562789D01*
G01X1638871D02*
Y574455D01*
G01Y572414D02*
X1637998Y573580D01*
X1636687Y574164D01*
X1635159Y574455D01*
X1633631Y573872D01*
X1632321Y572706D01*
X1631447Y570956D01*
X1631011Y568622D01*
X1631447Y566289D01*
X1632321Y564539D01*
X1633631Y563372D01*
X1635159Y562789D01*
X1636687Y563081D01*
X1637998Y563955D01*
X1638871Y565122D01*
G01X1649384Y562789D02*
Y574455D01*
G01Y572122D02*
X1650476Y573289D01*
X1651568Y574164D01*
X1653096Y574455D01*
X1654187Y574164D01*
X1655498Y573289D01*
G01X1673871Y580289D02*
Y562789D01*
G01Y565413D02*
X1672998Y563955D01*
X1671687Y563081D01*
X1670159Y562789D01*
X1668413Y563372D01*
X1667103Y564830D01*
X1666229Y566580D01*
X1666011Y568622D01*
X1666229Y570664D01*
X1667103Y572414D01*
X1668413Y573872D01*
X1670159Y574455D01*
X1671687Y574164D01*
X1672779Y573580D01*
X1673871Y572414D01*
G01X1704941Y562789D02*
X1703631Y563081D01*
X1702321Y564247D01*
X1701447Y566289D01*
X1701011Y568622D01*
X1701447Y570956D01*
X1702321Y572997D01*
X1703631Y574164D01*
X1704941Y574455D01*
X1706251Y574164D01*
X1707561Y572997D01*
X1708434Y570956D01*
X1708653Y568622D01*
X1708434Y566289D01*
X1707561Y564247D01*
X1706251Y563081D01*
X1704941Y562789D01*
G01X1718729Y574455D02*
Y566289D01*
X1719603Y564247D01*
X1720913Y563081D01*
X1722441Y562789D01*
X1723969Y563081D01*
X1725279Y564247D01*
X1726153Y566289D01*
G01Y562789D02*
Y574455D01*
G01X1739941Y580289D02*
Y562789D01*
G01X1736884Y574455D02*
X1742998D01*
G01X1757441Y562789D02*
Y580289D01*
G01X1774941Y574455D02*
Y562789D01*
G01Y579122D02*
X1774504Y579414D01*
Y579997D01*
X1774941Y580289D01*
X1775378Y579997D01*
Y579414D01*
X1774941Y579122D01*
G01X1788729Y562789D02*
Y574455D01*
G01Y571539D02*
X1789603Y572997D01*
X1790913Y574164D01*
X1792659Y574455D01*
X1794187Y574164D01*
X1795498Y572997D01*
X1796153Y570956D01*
Y562789D01*
G01X1806666Y570664D02*
X1813653D01*
X1812998Y572706D01*
X1811906Y573872D01*
X1810378Y574455D01*
X1808849Y574164D01*
X1807539Y573289D01*
X1806666Y571247D01*
X1806229Y569497D01*
Y567747D01*
X1806666Y565997D01*
X1807758Y564247D01*
X1809068Y563081D01*
X1810596Y562789D01*
X1812124Y563372D01*
X1813653Y565122D01*
G01X1827441Y562206D02*
X1827004Y562497D01*
Y563081D01*
X1827441Y563372D01*
X1827878Y563081D01*
Y562497D01*
X1827441Y562206D01*
G01X1402638Y631506D02*
X1412244Y644339D01*
G01X1407441Y646672D02*
Y629172D01*
G01X1412244Y631506D02*
X1402638Y644339D01*
G01X1400891Y637922D02*
X1413991D01*
G01X1439603D02*
X1445279D01*
G01X1472638Y632089D02*
Y649589D01*
X1477004D01*
X1478751Y648714D01*
X1480061Y647547D01*
X1481153Y645798D01*
X1482026Y643755D01*
X1482244Y640839D01*
X1482026Y637922D01*
X1481153Y635880D01*
X1480061Y634130D01*
X1478751Y632964D01*
X1477004Y632089D01*
X1472638D01*
G01X1491666Y639964D02*
X1498653D01*
X1497998Y642006D01*
X1496906Y643172D01*
X1495378Y643755D01*
X1493849Y643464D01*
X1492539Y642589D01*
X1491666Y640547D01*
X1491229Y638797D01*
Y637047D01*
X1491666Y635297D01*
X1492758Y633547D01*
X1494068Y632381D01*
X1495596Y632089D01*
X1497124Y632672D01*
X1498653Y634422D01*
G01X1508729Y632089D02*
Y643755D01*
G01Y640839D02*
X1509603Y642297D01*
X1510913Y643464D01*
X1512659Y643755D01*
X1514187Y643464D01*
X1515498Y642297D01*
X1516153Y640256D01*
Y632089D01*
G01X1529941D02*
X1528631Y632381D01*
X1527321Y633547D01*
X1526447Y635589D01*
X1526011Y637922D01*
X1526447Y640256D01*
X1527321Y642297D01*
X1528631Y643464D01*
X1529941Y643755D01*
X1531251Y643464D01*
X1532561Y642297D01*
X1533434Y640256D01*
X1533653Y637922D01*
X1533434Y635589D01*
X1532561Y633547D01*
X1531251Y632381D01*
X1529941Y632089D01*
G01X1547441Y649589D02*
Y632089D01*
G01X1544384Y643755D02*
X1550498D01*
G01X1561666Y639964D02*
X1568653D01*
X1567998Y642006D01*
X1566906Y643172D01*
X1565378Y643755D01*
X1563849Y643464D01*
X1562539Y642589D01*
X1561666Y640547D01*
X1561229Y638797D01*
Y637047D01*
X1561666Y635297D01*
X1562758Y633547D01*
X1564068Y632381D01*
X1565596Y632089D01*
X1567124Y632672D01*
X1568653Y634422D01*
G01X1579166Y634130D02*
X1580258Y632964D01*
X1581786Y632089D01*
X1583096D01*
X1584406Y632672D01*
X1585279Y633547D01*
X1585716Y634713D01*
X1585498Y636464D01*
X1584624Y637339D01*
X1580694Y639089D01*
X1579821Y641131D01*
X1580258Y642589D01*
X1581131Y643464D01*
X1582441Y643755D01*
X1583751Y643464D01*
X1585061Y642589D01*
G01X1617441Y649589D02*
Y632089D01*
G01X1614384Y643755D02*
X1620498D01*
G01X1631229Y632089D02*
Y649589D01*
G01Y641131D02*
X1632321Y642589D01*
X1633413Y643464D01*
X1635159Y643755D01*
X1636469Y643464D01*
X1637998Y642297D01*
X1638653Y640547D01*
Y632089D01*
G01X1656371D02*
Y643755D01*
G01Y641714D02*
X1655498Y642880D01*
X1654187Y643464D01*
X1652659Y643755D01*
X1651131Y643172D01*
X1649821Y642006D01*
X1648947Y640256D01*
X1648511Y637922D01*
X1648947Y635589D01*
X1649821Y633839D01*
X1651131Y632672D01*
X1652659Y632089D01*
X1654187Y632381D01*
X1655498Y633255D01*
X1656371Y634422D01*
G01X1669941Y649589D02*
Y632089D01*
G01X1666884Y643755D02*
X1672998D01*
G01X1698391Y649589D02*
X1701447Y632089D01*
X1704941Y649589D01*
X1708434Y632089D01*
X1711491Y649589D01*
G01X1719821D02*
X1725061D01*
G01X1722441D02*
Y632089D01*
G01X1719821D02*
X1725061D01*
G01X1735138D02*
Y649589D01*
X1739504D01*
X1741251Y648714D01*
X1742561Y647547D01*
X1743653Y645798D01*
X1744526Y643755D01*
X1744744Y640839D01*
X1744526Y637922D01*
X1743653Y635880D01*
X1742561Y634130D01*
X1741251Y632964D01*
X1739504Y632089D01*
X1735138D01*
G01X1757441Y649589D02*
Y632089D01*
G01X1752419Y649589D02*
X1762463D01*
G01X1770356Y632089D02*
Y649589D01*
G01X1779526D02*
Y632089D01*
G01Y640839D02*
X1770356D01*
G01X1477441Y609105D02*
Y597439D01*
G01Y613772D02*
X1477004Y614064D01*
Y614647D01*
X1477441Y614939D01*
X1477878Y614647D01*
Y614064D01*
X1477441Y613772D01*
G01X1491666Y599480D02*
X1492758Y598314D01*
X1494286Y597439D01*
X1495596D01*
X1496906Y598022D01*
X1497779Y598897D01*
X1498216Y600063D01*
X1497998Y601814D01*
X1497124Y602689D01*
X1493194Y604439D01*
X1492321Y606481D01*
X1492758Y607939D01*
X1493631Y608814D01*
X1494941Y609105D01*
X1496251Y608814D01*
X1497561Y607939D01*
G01X1524919Y597439D02*
Y614939D01*
X1534963Y597439D01*
Y614939D01*
G01X1547441Y597439D02*
X1545694Y597731D01*
X1544166Y598897D01*
X1542856Y600647D01*
X1541982Y602689D01*
X1541546Y605022D01*
Y607356D01*
X1541982Y609689D01*
X1542856Y611731D01*
X1544166Y613480D01*
X1545694Y614647D01*
X1547441Y614939D01*
X1549187Y614647D01*
X1550716Y613480D01*
X1552026Y611731D01*
X1552900Y609689D01*
X1553336Y607356D01*
Y605022D01*
X1552900Y602689D01*
X1552026Y600647D01*
X1550716Y598897D01*
X1549187Y597731D01*
X1547441Y597439D01*
G01X1564941Y614939D02*
Y597439D01*
G01X1559919Y614939D02*
X1569963D01*
G01X1596229Y609105D02*
Y600939D01*
X1597103Y598897D01*
X1598413Y597731D01*
X1599941Y597439D01*
X1601469Y597731D01*
X1602779Y598897D01*
X1603653Y600939D01*
G01Y597439D02*
Y609105D01*
G01X1614166Y599480D02*
X1615258Y598314D01*
X1616786Y597439D01*
X1618096D01*
X1619406Y598022D01*
X1620279Y598897D01*
X1620716Y600063D01*
X1620498Y601814D01*
X1619624Y602689D01*
X1615694Y604439D01*
X1614821Y606481D01*
X1615258Y607939D01*
X1616131Y608814D01*
X1617441Y609105D01*
X1618751Y608814D01*
X1620061Y607939D01*
G01X1631666Y605314D02*
X1638653D01*
X1637998Y607356D01*
X1636906Y608522D01*
X1635378Y609105D01*
X1633849Y608814D01*
X1632539Y607939D01*
X1631666Y605897D01*
X1631229Y604147D01*
Y602397D01*
X1631666Y600647D01*
X1632758Y598897D01*
X1634068Y597731D01*
X1635596Y597439D01*
X1637124Y598022D01*
X1638653Y599772D01*
G01X1656371Y614939D02*
Y597439D01*
G01Y600063D02*
X1655498Y598605D01*
X1654187Y597731D01*
X1652659Y597439D01*
X1650913Y598022D01*
X1649603Y599480D01*
X1648729Y601230D01*
X1648511Y603272D01*
X1648729Y605314D01*
X1649603Y607064D01*
X1650913Y608522D01*
X1652659Y609105D01*
X1654187Y608814D01*
X1655279Y608230D01*
X1656371Y607064D01*
G01X1687441Y609105D02*
Y597439D01*
G01Y613772D02*
X1687004Y614064D01*
Y614647D01*
X1687441Y614939D01*
X1687878Y614647D01*
Y614064D01*
X1687441Y613772D01*
G01X1701229Y597439D02*
Y609105D01*
G01Y606189D02*
X1702103Y607647D01*
X1703413Y608814D01*
X1705159Y609105D01*
X1706687Y608814D01*
X1707998Y607647D01*
X1708653Y605606D01*
Y597439D01*
G01X1739941Y614939D02*
Y597439D01*
G01X1736884Y609105D02*
X1742998D01*
G01X1753729Y597439D02*
Y614939D01*
G01Y606481D02*
X1754821Y607939D01*
X1755913Y608814D01*
X1757659Y609105D01*
X1758969Y608814D01*
X1760498Y607647D01*
X1761153Y605897D01*
Y597439D01*
G01X1774941Y609105D02*
Y597439D01*
G01Y613772D02*
X1774504Y614064D01*
Y614647D01*
X1774941Y614939D01*
X1775378Y614647D01*
Y614064D01*
X1774941Y613772D01*
G01X1789166Y599480D02*
X1790258Y598314D01*
X1791786Y597439D01*
X1793096D01*
X1794406Y598022D01*
X1795279Y598897D01*
X1795716Y600063D01*
X1795498Y601814D01*
X1794624Y602689D01*
X1790694Y604439D01*
X1789821Y606481D01*
X1790258Y607939D01*
X1791131Y608814D01*
X1792441Y609105D01*
X1793751Y608814D01*
X1795061Y607939D01*
G01X1827441Y597439D02*
Y614939D01*
G01X1848871Y597439D02*
Y609105D01*
G01Y607064D02*
X1847998Y608230D01*
X1846687Y608814D01*
X1845159Y609105D01*
X1843631Y608522D01*
X1842321Y607356D01*
X1841447Y605606D01*
X1841011Y603272D01*
X1841447Y600939D01*
X1842321Y599189D01*
X1843631Y598022D01*
X1845159Y597439D01*
X1846687Y597731D01*
X1847998Y598605D01*
X1848871Y599772D01*
G01X1857856Y592189D02*
X1859166Y591606D01*
X1860913Y592189D01*
X1862004Y593355D01*
X1862878Y594814D01*
X1864187Y599480D01*
X1867026Y609105D01*
G01X1860039D02*
X1864187Y599480D01*
G01X1876666Y605314D02*
X1883653D01*
X1882998Y607356D01*
X1881906Y608522D01*
X1880378Y609105D01*
X1878849Y608814D01*
X1877539Y607939D01*
X1876666Y605897D01*
X1876229Y604147D01*
Y602397D01*
X1876666Y600647D01*
X1877758Y598897D01*
X1879068Y597731D01*
X1880596Y597439D01*
X1882124Y598022D01*
X1883653Y599772D01*
G01X1894384Y597439D02*
Y609105D01*
G01Y606772D02*
X1895476Y607939D01*
X1896568Y608814D01*
X1898096Y609105D01*
X1899187Y608814D01*
X1900498Y607939D01*
G01X-20271Y15000D02*
Y676339D01*
G01Y15000D02*
G03X-5271Y0I15000J0D01*
G01Y691339D02*
G03X-20271Y676339I0J-15000D01*
G01X0Y37795D02*
G03X3937Y33858I3937J0D01*
G01X21063Y29921D02*
G03X17126Y33858I-3937J0D01*
G01X3937D02*
X17126D01*
G01X299409Y0D02*
X23031D01*
G01X21063Y1969D02*
X23031Y0D01*
G01X21063Y1969D02*
Y29921D01*
G01X0Y102756D02*
Y37795D01*
G01D02*
G03X-7874I-3937J0D01*
G01X3937Y25984D02*
X13189D01*
G01X-7874Y37795D02*
G03X3937Y25984I11811J0D01*
G01X13189Y0D02*
X-5271D01*
G01X13189Y25984D02*
Y0D01*
G01X3937Y106693D02*
G03X0Y102756I0J-3937D01*
G01X-7874Y68504D02*
G03X0I3937J0D01*
G01X-7874D02*
Y122737D01*
G01X0Y118504D02*
G03X3937Y114567I3937J0D01*
G01Y157382D02*
G03X0Y153445I0J-3937D01*
G01X17126Y157382D02*
G03X21063Y161319I0J3937D01*
G01X0Y118504D02*
Y153445D01*
G01X21063Y219292D02*
Y161319D01*
G01D02*
Y187402D01*
G01X143701Y114567D02*
X3937D01*
G01Y157382D02*
X17126D01*
G01X3937Y106693D02*
X143701D01*
G01X-7874Y153445D02*
Y157382D01*
G01Y153445D02*
G03X0I3937J0D01*
G01Y122737D02*
G03X-7874I-3937J0D01*
G01X-10433Y161070D02*
G03X-7874Y157382I3937J0D01*
G01X-10433Y265210D02*
Y161070D01*
G01X51378Y181496D02*
G03X47441Y177559I0J-3937D01*
G01Y165748D02*
G03X51378Y161811I3937J0D01*
G01X47441Y165748D02*
Y177559D01*
G01X23031Y221260D02*
X21063Y219292D01*
G01X23031Y221260D02*
X63189D01*
G01X0Y272835D02*
G03X3937Y268898I3937J0D01*
G01X21063Y264961D02*
G03X17126Y268898I-3937J0D01*
G01X3937D02*
X17126D01*
G01X299409Y235040D02*
X23031D01*
G01X21063Y237008D02*
X23031Y235040D01*
G01X21063Y237008D02*
Y264961D01*
G01X0Y337796D02*
Y272835D01*
G01D02*
G03X-7874I-3937J0D01*
G01Y268898D02*
G03X-10433Y265210I1378J-3688D01*
G01X-7874Y268898D02*
Y272835D01*
G01X3937Y341733D02*
G03X0Y337796I0J-3937D01*
G01X3937Y341733D02*
X143701D01*
G01X-7874Y303543D02*
Y357781D01*
G01Y303544D02*
G03X0I3937J0D01*
G01X47441Y400788D02*
G03X51378Y396851I3937J0D01*
G01X47441Y400788D02*
Y412599D01*
G01X0Y353544D02*
G03X3937Y349607I3937J0D01*
G01Y392422D02*
G03X0Y388485I0J-3937D01*
G01X17126Y392422D02*
G03X21063Y396359I0J3937D01*
G01X0Y353544D02*
Y388485D01*
G01X21063Y454331D02*
Y396359D01*
G01D02*
Y422441D01*
G01X143701Y349607D02*
X3937D01*
G01Y392422D02*
X17126D01*
G01X-7874Y388480D02*
Y392422D01*
G01Y388485D02*
G03X0I3937J0D01*
G01Y357776D02*
G03X-7874I-3937J0D01*
G01X-10433Y396110D02*
G03X-7874Y392422I3937J0D01*
G01X-10433Y500250D02*
Y396110D01*
G01X51378Y416536D02*
G03X47441Y412599I0J-3937D01*
G01X23031Y456300D02*
X21063Y454331D01*
G01X23031Y456300D02*
X63189D01*
G01X0Y507874D02*
G03X3937Y503937I3937J0D01*
G01X21063Y500000D02*
G03X17126Y503937I-3937J0D01*
G01X3937D02*
X17126D01*
G01X299409Y470079D02*
X23031D01*
G01X21063Y472048D02*
X23031Y470079D01*
G01X21063Y472048D02*
Y500000D01*
G01X0Y572835D02*
Y507874D01*
G01D02*
G03X-7874I-3937J0D01*
G01Y503937D02*
Y507880D01*
G01Y503937D02*
G03X-10433Y500250I1378J-3688D01*
G01X3937Y576772D02*
G03X0Y572835I0J-3937D01*
G01X3937Y576772D02*
X143701D01*
G01X0Y588583D02*
G03X3937Y584646I3937J0D01*
G01X0Y588583D02*
Y623524D01*
G01X143701Y584646D02*
X3937D01*
G01X-7874Y538578D02*
Y592823D01*
G01Y538583D02*
G03X0I3937J0D01*
G01X51378Y651576D02*
G03X47441Y647639I0J-3937D01*
G01Y635828D02*
G03X51378Y631891I3937J0D01*
G01X47441Y635828D02*
Y647639D01*
G01X3937Y627461D02*
G03X0Y623524I0J-3937D01*
G01X17126Y627461D02*
G03X21063Y631398I0J3937D01*
G01Y689371D02*
Y631398D01*
G01D02*
Y657481D01*
G01X3937Y627461D02*
X17126D01*
G01X1830Y651994D02*
G03I-4292J0D01*
G01X-7874Y623517D02*
Y623536D01*
G01X13189Y691339D02*
Y635335D01*
G01X3937D02*
X13189D01*
G01X3937D02*
G03X-7874Y623524I0J-11811D01*
G01D02*
G03X0I3937J0D01*
G01Y592816D02*
G03X-7874I-3937J0D01*
G01X23031Y691339D02*
X21063Y689371D01*
G01X23031Y691339D02*
X63189D01*
G01X13189D02*
X-5271D01*
G01X63189Y161811D02*
G03X67126Y165748I0J3937D01*
G01X73425D02*
G03X77362Y161811I3937J0D01*
G01X89173D02*
G03X93110Y165748I0J3937D01*
G01X99409D02*
G03X103346Y161811I3937J0D01*
G01X63189D02*
X51378D01*
G01X89173D02*
X77362D01*
G01X115157D02*
X103346D01*
G01X89173Y114567D02*
G03Y106693I0J-3937D01*
G01X58465D02*
G03Y114567I0J3937D01*
G01X67126Y177559D02*
G03X63189Y181496I-3937J0D01*
G01X77362D02*
G03X73425Y177559I0J-3937D01*
G01X93110D02*
G03X89173Y181496I-3937J0D01*
G01X103346D02*
G03X99409Y177559I0J-3937D01*
G01X67126D02*
Y165748D01*
G01X73425D02*
Y177559D01*
G01X93110D02*
Y165748D01*
G01X99409D02*
Y177559D01*
G01X103346Y181496D02*
X115157D01*
G01X77362D02*
X89173D01*
G01X51378D02*
X63189D01*
G01X65157Y191930D02*
G03X72638I3740J0D01*
G01X65157Y219292D02*
Y191930D01*
G01X74606Y221260D02*
X72638Y219292D01*
G01D02*
Y191930D01*
G01X65157Y219292D02*
X63189Y221260D01*
G01X74606D02*
X350984D01*
G01X89173Y349607D02*
G03Y341733I0J-3937D01*
G01X58465D02*
G03Y349607I0J3937D01*
G01X63189Y396851D02*
G03X67126Y400788I0J3937D01*
G01X73425D02*
G03X77362Y396851I3937J0D01*
G01X89173D02*
G03X93110Y400788I0J3937D01*
G01X99409D02*
G03X103346Y396851I3937J0D01*
G01X67126Y412599D02*
Y400788D01*
G01X73425D02*
Y412599D01*
G01X93110D02*
Y400788D01*
G01X99409D02*
Y412599D01*
G01X63189Y396851D02*
X51378D01*
G01X89173D02*
X77362D01*
G01X115157D02*
X103346D01*
G01X67126Y412599D02*
G03X63189Y416536I-3937J0D01*
G01X77362D02*
G03X73425Y412599I0J-3937D01*
G01X93110D02*
G03X89173Y416536I-3937J0D01*
G01X103346D02*
G03X99409Y412599I0J-3937D01*
G01X103346Y416536D02*
X115157D01*
G01X77362D02*
X89173D01*
G01X51378D02*
X63189D01*
G01X65157Y426969D02*
G03X72638I3740J0D01*
G01X65157Y454331D02*
Y426969D01*
G01X74606Y456300D02*
X72638Y454331D01*
G01D02*
Y426969D01*
G01X65157Y454331D02*
X63189Y456300D01*
G01X74606D02*
X350984D01*
G01X89173Y584646D02*
G03Y576772I0J-3937D01*
G01X58465D02*
G03Y584646I0J3937D01*
G01X67126Y647639D02*
G03X63189Y651576I-3937J0D01*
G01Y631891D02*
G03X67126Y635828I0J3937D01*
G01X73425D02*
G03X77362Y631891I3937J0D01*
G01Y651576D02*
G03X73425Y647639I0J-3937D01*
G01X93110D02*
G03X89173Y651576I-3937J0D01*
G01Y631891D02*
G03X93110Y635828I0J3937D01*
G01X103346Y651576D02*
G03X99409Y647639I0J-3937D01*
G01Y635828D02*
G03X103346Y631891I3937J0D01*
G01X67126Y647639D02*
Y635828D01*
G01X73425D02*
Y647639D01*
G01X93110D02*
Y635828D01*
G01X99409D02*
Y647639D01*
G01X63189Y631891D02*
X51378D01*
G01X89173D02*
X77362D01*
G01X115157D02*
X103346D01*
G01Y651576D02*
X115157D01*
G01X77362D02*
X89173D01*
G01X51378D02*
X63189D01*
G01X65157Y662009D02*
G03X72638I3740J0D01*
G01X65157Y689371D02*
Y662009D01*
G01X74606Y691339D02*
X72638Y689371D01*
G01D02*
Y662009D01*
G01X65157Y689371D02*
X63189Y691339D01*
G01X74606D02*
X350984D01*
G01X147638Y102756D02*
G03X151575Y98819I3937J0D01*
G01X147638Y102756D02*
G03X143701Y106693I-3937J0D01*
G01X147638Y102756D02*
G03X151575Y98819I3937J0D01*
G01X147638Y102756D02*
G03X143701Y106693I-3937J0D01*
G01X147638Y102756D02*
G03X151575Y98819I3937J0D01*
G01X147638Y102756D02*
G03X143701Y106693I-3937J0D01*
G01X151575Y98819D02*
X222441D01*
G01X115157Y161811D02*
G03X119094Y165748I0J3937D01*
G01X151575Y122441D02*
G03X147638Y118504I0J-3937D01*
G01X143701Y114567D02*
G03X147638Y118504I0J3937D01*
G01X143701Y114567D02*
X112205D01*
G01X143701D02*
G03X147638Y118504I0J3937D01*
G01X151575Y122441D02*
G03X147638Y118504I0J-3937D01*
G01X151575Y122441D02*
G03X147638Y118504I0J-3937D01*
G01X143701Y114567D02*
G03X147638Y118504I0J3937D01*
G01X222441Y122441D02*
X151575D01*
G01X143701Y106693D02*
X112205D01*
G01X119094Y177559D02*
G03X115157Y181496I-3937J0D01*
G01X119094Y177559D02*
Y165748D01*
G01X147638Y337796D02*
G03X151575Y333859I3937J0D01*
G01X147638Y337796D02*
G03X143701Y341733I-3937J0D01*
G01D02*
X112205D01*
G01X147638Y337796D02*
G03X151575Y333859I3937J0D01*
G01X147638Y337796D02*
G03X143701Y341733I-3937J0D01*
G01X147638Y337796D02*
G03X151575Y333859I3937J0D01*
G01X147638Y337796D02*
G03X143701Y341733I-3937J0D01*
G01X151575Y333859D02*
X222441D01*
G01X115157Y396851D02*
G03X119094Y400788I0J3937D01*
G01Y412599D02*
Y400788D01*
G01X151575Y357481D02*
G03X147638Y353544I0J-3937D01*
G01X143701Y349607D02*
G03X147638Y353544I0J3937D01*
G01X143701Y349607D02*
X112205D01*
G01X143701D02*
G03X147638Y353544I0J3937D01*
G01X151575Y357481D02*
G03X147638Y353544I0J-3937D01*
G01X151575Y357481D02*
G03X147638Y353544I0J-3937D01*
G01X143701Y349607D02*
G03X147638Y353544I0J3937D01*
G01X222441Y357481D02*
X151575D01*
G01X119094Y412599D02*
G03X115157Y416536I-3937J0D01*
G01X147638Y572835D02*
G03X151575Y568898I3937J0D01*
G01X147638Y572835D02*
G03X143701Y576772I-3937J0D01*
G01D02*
X112205D01*
G01X147638Y572835D02*
G03X151575Y568898I3937J0D01*
G01X147638Y572835D02*
G03X143701Y576772I-3937J0D01*
G01X147638Y572835D02*
G03X151575Y568898I3937J0D01*
G01X147638Y572835D02*
G03X143701Y576772I-3937J0D01*
G01X151575Y568898D02*
X222441D01*
G01X151575Y592520D02*
G03X147638Y588583I0J-3937D01*
G01X143701Y584646D02*
G03X147638Y588583I0J3937D01*
G01X143701Y584646D02*
X112205D01*
G01X143701D02*
G03X147638Y588583I0J3937D01*
G01X151575Y592520D02*
G03X147638Y588583I0J-3937D01*
G01X151575Y592520D02*
G03X147638Y588583I0J-3937D01*
G01X143701Y584646D02*
G03X147638Y588583I0J3937D01*
G01X119094Y647639D02*
G03X115157Y651576I-3937J0D01*
G01Y631891D02*
G03X119094Y635828I0J3937D01*
G01Y647639D02*
Y635828D01*
G01X222441Y592520D02*
X151575D01*
G01X222441Y98819D02*
G03X226378Y102756I0J3937D01*
G01X230315Y106693D02*
G03X226378Y102756I0J-3937D01*
G01X230315Y106693D02*
G03X226378Y102756I0J-3937D01*
G01X222441Y98819D02*
G03X226378Y102756I0J3937D01*
G01X222441Y98819D02*
G03X226378Y102756I0J3937D01*
G01X230315Y106693D02*
G03X226378Y102756I0J-3937D01*
G01Y118504D02*
G03X222441Y122441I-3937J0D01*
G01X226378Y118504D02*
G03X230315Y114567I3937J0D01*
G01D02*
X261811D01*
G01X226378Y118504D02*
G03X222441Y122441I-3937J0D01*
G01X226378Y118504D02*
G03X230315Y114567I3937J0D01*
G01X226378Y118504D02*
G03X222441Y122441I-3937J0D01*
G01X226378Y118504D02*
G03X230315Y114567I3937J0D01*
G01X370079D02*
X230315D01*
G01Y106693D02*
X261811D01*
G01X230315D02*
X370079D01*
G01X222441Y333859D02*
G03X226378Y337796I0J3937D01*
G01X230315Y341733D02*
G03X226378Y337796I0J-3937D01*
G01X230315Y341733D02*
X261811D01*
G01X230315D02*
G03X226378Y337796I0J-3937D01*
G01X222441Y333859D02*
G03X226378Y337796I0J3937D01*
G01X222441Y333859D02*
G03X226378Y337796I0J3937D01*
G01X230315Y341733D02*
G03X226378Y337796I0J-3937D01*
G01X230315Y341733D02*
X370079D01*
G01X226378Y353544D02*
G03X222441Y357481I-3937J0D01*
G01X226378Y353544D02*
G03X230315Y349607I3937J0D01*
G01D02*
X261811D01*
G01X226378Y353544D02*
G03X222441Y357481I-3937J0D01*
G01X226378Y353544D02*
G03X230315Y349607I3937J0D01*
G01X226378Y353544D02*
G03X222441Y357481I-3937J0D01*
G01X226378Y353544D02*
G03X230315Y349607I3937J0D01*
G01X370079D02*
X230315D01*
G01X222441Y568898D02*
G03X226378Y572835I0J3937D01*
G01X230315Y576772D02*
G03X226378Y572835I0J-3937D01*
G01X230315Y576772D02*
X261811D01*
G01X230315D02*
G03X226378Y572835I0J-3937D01*
G01X222441Y568898D02*
G03X226378Y572835I0J3937D01*
G01X222441Y568898D02*
G03X226378Y572835I0J3937D01*
G01X230315Y576772D02*
G03X226378Y572835I0J-3937D01*
G01X230315Y576772D02*
X370079D01*
G01X226378Y588583D02*
G03X222441Y592520I-3937J0D01*
G01X226378Y588583D02*
G03X230315Y584646I3937J0D01*
G01D02*
X261811D01*
G01X226378Y588583D02*
G03X222441Y592520I-3937J0D01*
G01X226378Y588583D02*
G03X230315Y584646I3937J0D01*
G01X226378Y588583D02*
G03X222441Y592520I-3937J0D01*
G01X226378Y588583D02*
G03X230315Y584646I3937J0D01*
G01X370079D02*
X230315D01*
G01X280906Y43701D02*
G03X284843Y39764I3937J0D01*
G01X270669D02*
G03X274606Y43701I0J3937D01*
G01X254921D02*
G03X258858Y39764I3937J0D01*
G01X270669D02*
X258858D01*
G01X296654D02*
X284843D01*
G01Y59449D02*
G03X280906Y55512I0J-3937D01*
G01X258858Y59449D02*
G03X254921Y55512I0J-3937D01*
G01X274606D02*
G03X270669Y59449I-3937J0D01*
G01X280906Y43701D02*
Y55512D01*
G01X274606D02*
Y43701D01*
G01X254921D02*
Y55512D01*
G01X284843Y59449D02*
X296654D01*
G01X258858D02*
X270669D01*
G01X284843Y106693D02*
G03Y114567I0J3937D01*
G01X280906Y278741D02*
G03X284843Y274804I3937J0D01*
G01X270669D02*
G03X274606Y278741I0J3937D01*
G01X254921D02*
G03X258858Y274804I3937J0D01*
G01X280906Y278741D02*
Y290552D01*
G01X274606D02*
Y278741D01*
G01X254921D02*
Y290552D01*
G01X270669Y274804D02*
X258858D01*
G01X296654D02*
X284843D01*
G01Y294489D02*
G03X280906Y290552I0J-3937D01*
G01X258858Y294489D02*
G03X254921Y290552I0J-3937D01*
G01X274606D02*
G03X270669Y294489I-3937J0D01*
G01X284843D02*
X296654D01*
G01X258858D02*
X270669D01*
G01X284843Y341733D02*
G03Y349607I0J3937D01*
G01X280906Y513780D02*
G03X284843Y509843I3937J0D01*
G01Y529528D02*
G03X280906Y525591I0J-3937D01*
G01X270669Y509843D02*
G03X274606Y513780I0J3937D01*
G01X254921D02*
G03X258858Y509843I3937J0D01*
G01Y529528D02*
G03X254921Y525591I0J-3937D01*
G01X274606D02*
G03X270669Y529528I-3937J0D01*
G01X280906Y513780D02*
Y525591D01*
G01X274606D02*
Y513780D01*
G01X254921D02*
Y525591D01*
G01X284843Y529528D02*
X296654D01*
G01X258858D02*
X270669D01*
G01Y509843D02*
X258858D01*
G01X296654D02*
X284843D01*
G01Y576772D02*
G03Y584646I0J3937D01*
G01X322638Y39764D02*
G03X326575Y43701I0J3937D01*
G01X306890D02*
G03X310827Y39764I3937J0D01*
G01X296654D02*
G03X300591Y43701I0J3937D01*
G01X322638Y39764D02*
X310827D01*
G01X308858Y29331D02*
G03X301378I-3740J0D01*
G01X350984Y0D02*
X352953Y1969D01*
G01X308858D02*
Y29331D01*
G01X299409Y0D02*
X301378Y1969D01*
G01D02*
Y29331D01*
G01X308858Y1969D02*
X310827Y0D01*
G01X350984D02*
X310827D01*
G01Y59449D02*
G03X306890Y55512I0J-3937D01*
G01X326575D02*
G03X322638Y59449I-3937J0D01*
G01X300591Y55512D02*
G03X296654Y59449I-3937J0D01*
G01X326575Y55512D02*
Y43701D01*
G01X306890D02*
Y55512D01*
G01X300591D02*
Y43701D01*
G01X310827Y59449D02*
X322638D01*
G01X315551Y114567D02*
G03Y106693I0J-3937D01*
G01X352953Y219292D02*
X350984Y221260D01*
G01X322638Y274804D02*
G03X326575Y278741I0J3937D01*
G01X306890D02*
G03X310827Y274804I3937J0D01*
G01X296654D02*
G03X300591Y278741I0J3937D01*
G01X326575Y290552D02*
Y278741D01*
G01X306890D02*
Y290552D01*
G01X300591D02*
Y278741D01*
G01X322638Y274804D02*
X310827D01*
G01X308858Y264370D02*
G03X301378I-3740J0D01*
G01X350984Y235040D02*
X352953Y237008D01*
G01X308858D02*
Y264370D01*
G01X299409Y235040D02*
X301378Y237008D01*
G01D02*
Y264370D01*
G01X308858Y237008D02*
X310827Y235040D01*
G01X350984D02*
X310827D01*
G01Y294489D02*
G03X306890Y290552I0J-3937D01*
G01X326575D02*
G03X322638Y294489I-3937J0D01*
G01X300591Y290552D02*
G03X296654Y294489I-3937J0D01*
G01X310827D02*
X322638D01*
G01X315551Y349607D02*
G03Y341733I0J-3937D01*
G01X352953Y454331D02*
X350984Y456300D01*
G01X322638Y509843D02*
G03X326575Y513780I0J3937D01*
G01X306890D02*
G03X310827Y509843I3937J0D01*
G01Y529528D02*
G03X306890Y525591I0J-3937D01*
G01X326575D02*
G03X322638Y529528I-3937J0D01*
G01X300591Y525591D02*
G03X296654Y529528I-3937J0D01*
G01Y509843D02*
G03X300591Y513780I0J3937D01*
G01X326575Y525591D02*
Y513780D01*
G01X306890D02*
Y525591D01*
G01X300591D02*
Y513780D01*
G01X310827Y529528D02*
X322638D01*
G01Y509843D02*
X310827D01*
G01X308858Y499410D02*
G03X301378I-3740J0D01*
G01X350984Y470079D02*
X352953Y472048D01*
G01X308858D02*
Y499410D01*
G01X299409Y470079D02*
X301378Y472048D01*
G01D02*
Y499410D01*
G01X308858Y472048D02*
X310827Y470079D01*
G01X350984D02*
X310827D01*
G01X315551Y584646D02*
G03Y576772I0J-3937D01*
G01X352953Y689371D02*
X350984Y691339D01*
G01X381890Y37795D02*
G03X385827Y33858I3937J0D01*
G01X402953Y29921D02*
G03X399016Y33858I-3937J0D01*
G01X385827D02*
X399016D01*
G01X681299Y0D02*
X404921D01*
G01X402953Y1969D02*
X404921Y0D01*
G01X402953Y1969D02*
Y29921D01*
G01X381890Y102756D02*
Y37795D01*
G01X352953Y1969D02*
Y59941D01*
G01D02*
Y33858D01*
G01X385827Y106693D02*
G03X381890Y102756I0J-3937D01*
G01X374016D02*
G03X370079Y106693I-3937J0D01*
G01Y63878D02*
G03X374016Y67815I0J3937D01*
G01X356890Y63878D02*
G03X352953Y59941I0J-3937D01*
G01X374016Y102756D02*
Y67815D01*
G01X370079Y63878D02*
X356890D01*
G01X374016Y98524D02*
G03X381890I3937J0D01*
G01Y67815D02*
G03X374016I-3937J0D01*
G01X385827Y106693D02*
X525591D01*
G01X370079Y114567D02*
G03X374016Y118504I0J3937D01*
G01D02*
Y183465D01*
G01X381890Y118504D02*
G03X385827Y114567I3937J0D01*
G01Y157382D02*
G03X381890Y153445I0J-3937D01*
G01X399016Y157382D02*
G03X402953Y161319I0J3937D01*
G01X381890Y118504D02*
Y153445D01*
G01X402953Y219292D02*
Y161319D01*
G01D02*
Y187402D01*
G01X525591Y114567D02*
X385827D01*
G01Y157382D02*
X399016D01*
G01X374016Y153445D02*
G03X381890I3937J0D01*
G01Y122737D02*
G03X374016I-3937J0D01*
G01Y183465D02*
G03X370079Y187402I-3937J0D01*
G01X352953Y191339D02*
G03X356890Y187402I3937J0D01*
G01X370079D02*
X356890D01*
G01X352953Y219292D02*
Y191339D01*
G01X404921Y221260D02*
X402953Y219292D01*
G01X404921Y221260D02*
X445079D01*
G01X352953Y237008D02*
Y294981D01*
G01D02*
Y268898D01*
G01X381890Y272835D02*
G03X385827Y268898I3937J0D01*
G01X402953Y264961D02*
G03X399016Y268898I-3937J0D01*
G01X385827D02*
X399016D01*
G01X681299Y235040D02*
X404921D01*
G01X402953Y237008D02*
X404921Y235040D01*
G01X402953Y237008D02*
Y264961D01*
G01X381890Y337796D02*
Y272835D01*
G01X374016Y337796D02*
G03X370079Y341733I-3937J0D01*
G01Y298918D02*
G03X374016Y302855I0J3937D01*
G01X356890Y298918D02*
G03X352953Y294981I0J-3937D01*
G01X374016Y337796D02*
Y302855D01*
G01X370079Y298918D02*
X356890D01*
G01X385827Y341733D02*
G03X381890Y337796I0J-3937D01*
G01X385827Y341733D02*
X525591D01*
G01X374016Y333563D02*
G03X381890I3937J0D01*
G01Y302855D02*
G03X374016I-3937J0D01*
G01X381890Y353544D02*
G03X385827Y349607I3937J0D01*
G01Y392422D02*
G03X381890Y388485I0J-3937D01*
G01X399016Y392422D02*
G03X402953Y396359I0J3937D01*
G01X381890Y353544D02*
Y388485D01*
G01X402953Y454331D02*
Y396359D01*
G01D02*
Y422441D01*
G01X525591Y349607D02*
X385827D01*
G01Y392422D02*
X399016D01*
G01X370079Y349607D02*
G03X374016Y353544I0J3937D01*
G01D02*
Y418504D01*
G01Y388485D02*
G03X381890I3937J0D01*
G01Y357776D02*
G03X374016I-3937J0D01*
G01X404921Y456300D02*
X402953Y454331D01*
G01X404921Y456300D02*
X445079D01*
G01X374016Y418504D02*
G03X370079Y422441I-3937J0D01*
G01X352953Y426378D02*
G03X356890Y422441I3937J0D01*
G01X370079D02*
X356890D01*
G01X352953Y454331D02*
Y426378D01*
G01Y472048D02*
Y530020D01*
G01D02*
Y503937D01*
G01X381890Y507874D02*
G03X385827Y503937I3937J0D01*
G01X402953Y500000D02*
G03X399016Y503937I-3937J0D01*
G01X385827D02*
X399016D01*
G01X681299Y470079D02*
X404921D01*
G01X402953Y472048D02*
X404921Y470079D01*
G01X402953Y472048D02*
Y500000D01*
G01X381890Y572835D02*
Y507874D01*
G01X374016Y572835D02*
G03X370079Y576772I-3937J0D01*
G01Y533957D02*
G03X374016Y537894I0J3937D01*
G01X356890Y533957D02*
G03X352953Y530020I0J-3937D01*
G01X374016Y572835D02*
Y537894D01*
G01X370079Y533957D02*
X356890D01*
G01X385827Y576772D02*
G03X381890Y572835I0J-3937D01*
G01X385827Y576772D02*
X525591D01*
G01X381890Y588583D02*
G03X385827Y584646I3937J0D01*
G01X381890Y588583D02*
Y623524D01*
G01X525591Y584646D02*
X385827D01*
G01X370079D02*
G03X374016Y588583I0J3937D01*
G01D02*
Y653544D01*
G01Y568603D02*
G03X381890I3937J0D01*
G01Y537894D02*
G03X374016I-3937J0D01*
G01X385827Y627461D02*
G03X381890Y623524I0J-3937D01*
G01X399016Y627461D02*
G03X402953Y631398I0J3937D01*
G01Y689371D02*
Y631398D01*
G01D02*
Y657481D01*
G01X385827Y627461D02*
X399016D01*
G01X374016Y623524D02*
G03X381890I3937J0D01*
G01Y592816D02*
G03X374016I-3937J0D01*
G01X404921Y691339D02*
X402953Y689371D01*
G01X404921Y691339D02*
X445079D01*
G01X374016Y653544D02*
G03X370079Y657481I-3937J0D01*
G01X352953Y661418D02*
G03X356890Y657481I3937J0D01*
G01X370079D02*
X356890D01*
G01X352953Y689371D02*
Y661418D01*
G01X445079Y161811D02*
G03X449016Y165748I0J3937D01*
G01X429331D02*
G03X433268Y161811I3937J0D01*
G01X455315Y165748D02*
G03X459252Y161811I3937J0D01*
G01X471063D02*
G03X475000Y165748I0J3937D01*
G01X445079Y161811D02*
X433268D01*
G01X471063D02*
X459252D01*
G01X471063Y114567D02*
G03Y106693I0J-3937D01*
G01X440354D02*
G03Y114567I0J3937D01*
G01X433268Y181496D02*
G03X429331Y177559I0J-3937D01*
G01X449016D02*
G03X445079Y181496I-3937J0D01*
G01X459252D02*
G03X455315Y177559I0J-3937D01*
G01X475000D02*
G03X471063Y181496I-3937J0D01*
G01X429331Y165748D02*
Y177559D01*
G01X449016D02*
Y165748D01*
G01X455315D02*
Y177559D01*
G01X459252Y181496D02*
X471063D01*
G01X433268D02*
X445079D01*
G01X447047Y191930D02*
G03X454528I3740J0D01*
G01X447047Y219292D02*
Y191930D01*
G01X456496Y221260D02*
X454528Y219292D01*
G01D02*
Y191930D01*
G01X447047Y219292D02*
X445079Y221260D01*
G01X456496D02*
X732874D01*
G01X471063Y349607D02*
G03Y341733I0J-3937D01*
G01X440354D02*
G03Y349607I0J3937D01*
G01X445079Y396851D02*
G03X449016Y400788I0J3937D01*
G01X429331D02*
G03X433268Y396851I3937J0D01*
G01X455315Y400788D02*
G03X459252Y396851I3937J0D01*
G01X471063D02*
G03X475000Y400788I0J3937D01*
G01X429331D02*
Y412599D01*
G01X449016D02*
Y400788D01*
G01X455315D02*
Y412599D01*
G01X445079Y396851D02*
X433268D01*
G01X471063D02*
X459252D01*
G01X433268Y416536D02*
G03X429331Y412599I0J-3937D01*
G01X449016D02*
G03X445079Y416536I-3937J0D01*
G01X459252D02*
G03X455315Y412599I0J-3937D01*
G01X475000D02*
G03X471063Y416536I-3937J0D01*
G01X459252D02*
X471063D01*
G01X433268D02*
X445079D01*
G01X447047Y426969D02*
G03X454528I3740J0D01*
G01X447047Y454331D02*
Y426969D01*
G01X456496Y456300D02*
X454528Y454331D01*
G01D02*
Y426969D01*
G01X447047Y454331D02*
X445079Y456300D01*
G01X456496D02*
X732874D01*
G01X471063Y584646D02*
G03Y576772I0J-3937D01*
G01X440354D02*
G03Y584646I0J3937D01*
G01X433268Y651576D02*
G03X429331Y647639I0J-3937D01*
G01X449016D02*
G03X445079Y651576I-3937J0D01*
G01Y631891D02*
G03X449016Y635828I0J3937D01*
G01X429331D02*
G03X433268Y631891I3937J0D01*
G01X455315Y635828D02*
G03X459252Y631891I3937J0D01*
G01Y651576D02*
G03X455315Y647639I0J-3937D01*
G01X475000D02*
G03X471063Y651576I-3937J0D01*
G01Y631891D02*
G03X475000Y635828I0J3937D01*
G01X429331D02*
Y647639D01*
G01X449016D02*
Y635828D01*
G01X455315D02*
Y647639D01*
G01X445079Y631891D02*
X433268D01*
G01X471063D02*
X459252D01*
G01Y651576D02*
X471063D01*
G01X433268D02*
X445079D01*
G01X447047Y662009D02*
G03X454528I3740J0D01*
G01X447047Y689371D02*
Y662009D01*
G01X456496Y691339D02*
X454528Y689371D01*
G01D02*
Y662009D01*
G01X447047Y689371D02*
X445079Y691339D01*
G01X456496D02*
X732874D01*
G01X529528Y102756D02*
G03X533465Y98819I3937J0D01*
G01X529528Y102756D02*
G03X525591Y106693I-3937J0D01*
G01X529528Y102756D02*
G03X533465Y98819I3937J0D01*
G01X529528Y102756D02*
G03X525591Y106693I-3937J0D01*
G01X529528Y102756D02*
G03X533465Y98819I3937J0D01*
G01X529528Y102756D02*
G03X525591Y106693I-3937J0D01*
G01X533465Y98819D02*
X604331D01*
G01X525591Y106693D02*
X494094D01*
G01X497047Y161811D02*
G03X500984Y165748I0J3937D01*
G01X481299D02*
G03X485236Y161811I3937J0D01*
G01X497047D02*
X485236D01*
G01X533465Y122441D02*
G03X529528Y118504I0J-3937D01*
G01X525591Y114567D02*
G03X529528Y118504I0J3937D01*
G01X525591Y114567D02*
X494094D01*
G01X525591D02*
G03X529528Y118504I0J3937D01*
G01X533465Y122441D02*
G03X529528Y118504I0J-3937D01*
G01X533465Y122441D02*
G03X529528Y118504I0J-3937D01*
G01X525591Y114567D02*
G03X529528Y118504I0J3937D01*
G01X604331Y122441D02*
X533465D01*
G01X485236Y181496D02*
G03X481299Y177559I0J-3937D01*
G01X500984D02*
G03X497047Y181496I-3937J0D01*
G01X475000Y177559D02*
Y165748D01*
G01X481299D02*
Y177559D01*
G01X500984D02*
Y165748D01*
G01X485236Y181496D02*
X497047D01*
G01X529528Y337796D02*
G03X533465Y333859I3937J0D01*
G01X529528Y337796D02*
G03X525591Y341733I-3937J0D01*
G01D02*
X494094D01*
G01X529528Y337796D02*
G03X533465Y333859I3937J0D01*
G01X529528Y337796D02*
G03X525591Y341733I-3937J0D01*
G01X529528Y337796D02*
G03X533465Y333859I3937J0D01*
G01X529528Y337796D02*
G03X525591Y341733I-3937J0D01*
G01X533465Y333859D02*
X604331D01*
G01X497047Y396851D02*
G03X500984Y400788I0J3937D01*
G01X481299D02*
G03X485236Y396851I3937J0D01*
G01X475000Y412599D02*
Y400788D01*
G01X481299D02*
Y412599D01*
G01X500984D02*
Y400788D01*
G01X497047Y396851D02*
X485236D01*
G01X533465Y357481D02*
G03X529528Y353544I0J-3937D01*
G01X525591Y349607D02*
G03X529528Y353544I0J3937D01*
G01X525591Y349607D02*
X494094D01*
G01X525591D02*
G03X529528Y353544I0J3937D01*
G01X533465Y357481D02*
G03X529528Y353544I0J-3937D01*
G01X533465Y357481D02*
G03X529528Y353544I0J-3937D01*
G01X525591Y349607D02*
G03X529528Y353544I0J3937D01*
G01X604331Y357481D02*
X533465D01*
G01X485236Y416536D02*
G03X481299Y412599I0J-3937D01*
G01X500984D02*
G03X497047Y416536I-3937J0D01*
G01X485236D02*
X497047D01*
G01X529528Y572835D02*
G03X533465Y568898I3937J0D01*
G01X529528Y572835D02*
G03X525591Y576772I-3937J0D01*
G01D02*
X494094D01*
G01X529528Y572835D02*
G03X533465Y568898I3937J0D01*
G01X529528Y572835D02*
G03X525591Y576772I-3937J0D01*
G01X529528Y572835D02*
G03X533465Y568898I3937J0D01*
G01X529528Y572835D02*
G03X525591Y576772I-3937J0D01*
G01X533465Y568898D02*
X604331D01*
G01X533465Y592520D02*
G03X529528Y588583I0J-3937D01*
G01X525591Y584646D02*
G03X529528Y588583I0J3937D01*
G01X525591Y584646D02*
X494094D01*
G01X525591D02*
G03X529528Y588583I0J3937D01*
G01X533465Y592520D02*
G03X529528Y588583I0J-3937D01*
G01X533465Y592520D02*
G03X529528Y588583I0J-3937D01*
G01X525591Y584646D02*
G03X529528Y588583I0J3937D01*
G01X485236Y651576D02*
G03X481299Y647639I0J-3937D01*
G01X500984D02*
G03X497047Y651576I-3937J0D01*
G01Y631891D02*
G03X500984Y635828I0J3937D01*
G01X481299D02*
G03X485236Y631891I3937J0D01*
G01X475000Y647639D02*
Y635828D01*
G01X481299D02*
Y647639D01*
G01X500984D02*
Y635828D01*
G01X497047Y631891D02*
X485236D01*
G01Y651576D02*
X497047D01*
G01X604331Y592520D02*
X533465D01*
G01X652559Y39764D02*
G03X656496Y43701I0J3937D01*
G01X636811D02*
G03X640748Y39764I3937J0D01*
G01X652559D02*
X640748D01*
G01Y59449D02*
G03X636811Y55512I0J-3937D01*
G01X656496D02*
G03X652559Y59449I-3937J0D01*
G01X656496Y55512D02*
Y43701D01*
G01X636811D02*
Y55512D01*
G01X640748Y59449D02*
X652559D01*
G01X604331Y98819D02*
G03X608268Y102756I0J3937D01*
G01X612205Y106693D02*
G03X608268Y102756I0J-3937D01*
G01X612205Y106693D02*
G03X608268Y102756I0J-3937D01*
G01X604331Y98819D02*
G03X608268Y102756I0J3937D01*
G01X604331Y98819D02*
G03X608268Y102756I0J3937D01*
G01X612205Y106693D02*
G03X608268Y102756I0J-3937D01*
G01X612205Y106693D02*
X643701D01*
G01X612205D02*
X751969D01*
G01X608268Y118504D02*
G03X604331Y122441I-3937J0D01*
G01X608268Y118504D02*
G03X612205Y114567I3937J0D01*
G01D02*
X643701D01*
G01X608268Y118504D02*
G03X604331Y122441I-3937J0D01*
G01X608268Y118504D02*
G03X612205Y114567I3937J0D01*
G01X608268Y118504D02*
G03X604331Y122441I-3937J0D01*
G01X608268Y118504D02*
G03X612205Y114567I3937J0D01*
G01X751969D02*
X612205D01*
G01X652559Y274804D02*
G03X656496Y278741I0J3937D01*
G01X636811D02*
G03X640748Y274804I3937J0D01*
G01X656496Y290552D02*
Y278741D01*
G01X636811D02*
Y290552D01*
G01X652559Y274804D02*
X640748D01*
G01Y294489D02*
G03X636811Y290552I0J-3937D01*
G01X656496D02*
G03X652559Y294489I-3937J0D01*
G01X640748D02*
X652559D01*
G01X604331Y333859D02*
G03X608268Y337796I0J3937D01*
G01X612205Y341733D02*
G03X608268Y337796I0J-3937D01*
G01X612205Y341733D02*
X643701D01*
G01X612205D02*
G03X608268Y337796I0J-3937D01*
G01X604331Y333859D02*
G03X608268Y337796I0J3937D01*
G01X604331Y333859D02*
G03X608268Y337796I0J3937D01*
G01X612205Y341733D02*
G03X608268Y337796I0J-3937D01*
G01X612205Y341733D02*
X751969D01*
G01X608268Y353544D02*
G03X604331Y357481I-3937J0D01*
G01X608268Y353544D02*
G03X612205Y349607I3937J0D01*
G01D02*
X643701D01*
G01X608268Y353544D02*
G03X604331Y357481I-3937J0D01*
G01X608268Y353544D02*
G03X612205Y349607I3937J0D01*
G01X608268Y353544D02*
G03X604331Y357481I-3937J0D01*
G01X608268Y353544D02*
G03X612205Y349607I3937J0D01*
G01X751969D02*
X612205D01*
G01X652559Y509843D02*
G03X656496Y513780I0J3937D01*
G01X636811D02*
G03X640748Y509843I3937J0D01*
G01Y529528D02*
G03X636811Y525591I0J-3937D01*
G01X656496D02*
G03X652559Y529528I-3937J0D01*
G01X656496Y525591D02*
Y513780D01*
G01X636811D02*
Y525591D01*
G01X640748Y529528D02*
X652559D01*
G01Y509843D02*
X640748D01*
G01X604331Y568898D02*
G03X608268Y572835I0J3937D01*
G01X612205Y576772D02*
G03X608268Y572835I0J-3937D01*
G01X612205Y576772D02*
X643701D01*
G01X612205D02*
G03X608268Y572835I0J-3937D01*
G01X604331Y568898D02*
G03X608268Y572835I0J3937D01*
G01X604331Y568898D02*
G03X608268Y572835I0J3937D01*
G01X612205Y576772D02*
G03X608268Y572835I0J-3937D01*
G01X612205Y576772D02*
X751969D01*
G01X608268Y588583D02*
G03X604331Y592520I-3937J0D01*
G01X608268Y588583D02*
G03X612205Y584646I3937J0D01*
G01D02*
X643701D01*
G01X608268Y588583D02*
G03X604331Y592520I-3937J0D01*
G01X608268Y588583D02*
G03X612205Y584646I3937J0D01*
G01X608268Y588583D02*
G03X604331Y592520I-3937J0D01*
G01X608268Y588583D02*
G03X612205Y584646I3937J0D01*
G01X751969D02*
X612205D01*
G01X704528Y39764D02*
G03X708465Y43701I0J3937D01*
G01X688780D02*
G03X692717Y39764I3937J0D01*
G01X678543D02*
G03X682480Y43701I0J3937D01*
G01X662795D02*
G03X666732Y39764I3937J0D01*
G01X678543D02*
X666732D01*
G01X704528D02*
X692717D01*
G01X690748Y29331D02*
G03X683268I-3740J0D01*
G01X690748Y1969D02*
Y29331D01*
G01X681299Y0D02*
X683268Y1969D01*
G01D02*
Y29331D01*
G01X690748Y1969D02*
X692717Y0D01*
G01X732874D02*
X692717D01*
G01Y59449D02*
G03X688780Y55512I0J-3937D01*
G01X708465D02*
G03X704528Y59449I-3937J0D01*
G01X682480Y55512D02*
G03X678543Y59449I-3937J0D01*
G01X666732D02*
G03X662795Y55512I0J-3937D01*
G01X708465D02*
Y43701D01*
G01X688780D02*
Y55512D01*
G01X682480D02*
Y43701D01*
G01X662795D02*
Y55512D01*
G01X692717Y59449D02*
X704528D01*
G01X666732D02*
X678543D01*
G01X697441Y114567D02*
G03Y106693I0J-3937D01*
G01X666732D02*
G03Y114567I0J3937D01*
G01X704528Y274804D02*
G03X708465Y278741I0J3937D01*
G01X688780D02*
G03X692717Y274804I3937J0D01*
G01X678543D02*
G03X682480Y278741I0J3937D01*
G01X662795D02*
G03X666732Y274804I3937J0D01*
G01X708465Y290552D02*
Y278741D01*
G01X688780D02*
Y290552D01*
G01X682480D02*
Y278741D01*
G01X662795D02*
Y290552D01*
G01X678543Y274804D02*
X666732D01*
G01X704528D02*
X692717D01*
G01X690748Y264370D02*
G03X683268I-3740J0D01*
G01X690748Y237008D02*
Y264370D01*
G01X681299Y235040D02*
X683268Y237008D01*
G01D02*
Y264370D01*
G01X690748Y237008D02*
X692717Y235040D01*
G01X732874D02*
X692717D01*
G01Y294489D02*
G03X688780Y290552I0J-3937D01*
G01X708465D02*
G03X704528Y294489I-3937J0D01*
G01X682480Y290552D02*
G03X678543Y294489I-3937J0D01*
G01X666732D02*
G03X662795Y290552I0J-3937D01*
G01X692717Y294489D02*
X704528D01*
G01X666732D02*
X678543D01*
G01X697441Y349607D02*
G03Y341733I0J-3937D01*
G01X666732D02*
G03Y349607I0J3937D01*
G01X704528Y509843D02*
G03X708465Y513780I0J3937D01*
G01X688780D02*
G03X692717Y509843I3937J0D01*
G01Y529528D02*
G03X688780Y525591I0J-3937D01*
G01X708465D02*
G03X704528Y529528I-3937J0D01*
G01X682480Y525591D02*
G03X678543Y529528I-3937J0D01*
G01Y509843D02*
G03X682480Y513780I0J3937D01*
G01X662795D02*
G03X666732Y509843I3937J0D01*
G01Y529528D02*
G03X662795Y525591I0J-3937D01*
G01X708465D02*
Y513780D01*
G01X688780D02*
Y525591D01*
G01X682480D02*
Y513780D01*
G01X662795D02*
Y525591D01*
G01X692717Y529528D02*
X704528D01*
G01X666732D02*
X678543D01*
G01Y509843D02*
X666732D01*
G01X704528D02*
X692717D01*
G01X690748Y499410D02*
G03X683268I-3740J0D01*
G01X690748Y472048D02*
Y499410D01*
G01X681299Y470079D02*
X683268Y472048D01*
G01D02*
Y499410D01*
G01X690748Y472048D02*
X692717Y470079D01*
G01X732874D02*
X692717D01*
G01X697441Y584646D02*
G03Y576772I0J-3937D01*
G01X666732D02*
G03Y584646I0J3937D01*
G01X734843Y1969D02*
Y59941D01*
G01D02*
Y33858D01*
G01X732874Y0D02*
X734843Y1969D01*
G01X762744Y17317D02*
G03I-4292J0D01*
G01X775591Y553149D02*
Y15000D01*
G01X760591Y0D02*
G03X775591Y15000I0J15000D01*
G01X742717Y0D02*
Y56004D01*
G01Y0D02*
X760591D01*
G01X755906Y102756D02*
G03X751969Y106693I-3937J0D01*
G01Y63878D02*
G03X755906Y67815I0J3937D01*
G01X738780Y63878D02*
G03X734843Y59941I0J-3937D01*
G01X755906Y102756D02*
Y67815D01*
G01X751969Y63878D02*
X738780D01*
G01X763780Y152761D02*
Y98517D01*
G01Y67822D02*
Y67803D01*
G01X751969Y56004D02*
X742717D01*
G01X751969D02*
G03X763780Y67815I0J11811D01*
G01D02*
G03X755906I-3937J0D01*
G01Y98524D02*
G03X763780I3937J0D01*
G01X751969Y114567D02*
G03X755906Y118504I0J3937D01*
G01D02*
Y183465D01*
G01X763780Y152756D02*
G03X755906I-3937J0D01*
G01Y183465D02*
G03X751969Y187402I-3937J0D01*
G01X734843Y191339D02*
G03X738780Y187402I3937J0D01*
G01X751969D02*
X738780D01*
G01X734843Y219292D02*
X732874Y221260D01*
G01X734843Y219292D02*
Y191339D01*
G01X755906Y183465D02*
G03X763780I3937J0D01*
G01Y302855D02*
Y183460D01*
G01X734843Y237008D02*
Y294981D01*
G01D02*
Y268898D01*
G01X732874Y235040D02*
X734843Y237008D01*
G01X755906Y337796D02*
G03X751969Y341733I-3937J0D01*
G01Y298918D02*
G03X755906Y302855I0J3937D01*
G01X738780Y298918D02*
G03X734843Y294981I0J-3937D01*
G01X755906Y337796D02*
Y302855D01*
G01X751969Y298918D02*
X738780D01*
G01X763780Y387796D02*
Y333559D01*
G01Y302855D02*
G03X755906I-3937J0D01*
G01Y333563D02*
G03X763780I3937J0D01*
G01X751969Y349607D02*
G03X755906Y353544I0J3937D01*
G01D02*
Y418504D01*
G01X763780Y387796D02*
G03X755906I-3937J0D01*
G01Y418504D02*
G03X751969Y422441I-3937J0D01*
G01X734843Y426378D02*
G03X738780Y422441I3937J0D01*
G01X751969D02*
X738780D01*
G01X734843Y454331D02*
X732874Y456300D01*
G01X734843Y454331D02*
Y426378D01*
G01X763780Y537894D02*
Y418504D01*
G01X755906Y418505D02*
G03X763780I3937J0D01*
G01X734843Y472048D02*
Y530020D01*
G01D02*
Y503937D01*
G01X732874Y470079D02*
X734843Y472048D01*
G01X755906Y572835D02*
G03X751969Y576772I-3937J0D01*
G01Y533957D02*
G03X755906Y537894I0J3937D01*
G01X738780Y533957D02*
G03X734843Y530020I0J-3937D01*
G01X755906Y572835D02*
Y537894D01*
G01X751969Y533957D02*
X738780D01*
G01X751969Y584646D02*
G03X755906Y588583I0J3937D01*
G01D02*
Y653544D01*
G01X775591Y561023D02*
G03Y553149I0J-3937D01*
G01X763780Y537894D02*
G03X755906I-3937J0D01*
G01Y568603D02*
G03X763780I3937J0D01*
G01X775591Y676339D02*
Y561023D01*
G01X763780Y622835D02*
Y568603D01*
G01Y622835D02*
G03X755906I-3937J0D01*
G01Y653544D02*
G03X763780I3937J0D01*
G01X755906D02*
G03X751969Y657481I-3937J0D01*
G01X734843Y661418D02*
G03X738780Y657481I3937J0D01*
G01X751969D02*
X738780D01*
G01X734843Y689371D02*
X732874Y691339D01*
G01X734843Y689371D02*
Y661418D01*
G01X760014Y677788D02*
G03I-4292J0D01*
G01X775591Y676339D02*
G03X760591Y691339I-15000J0D01*
G01X751969Y665355D02*
X742717D01*
G01X763780Y653544D02*
G03X751969Y665355I-11811J0D01*
G01X742717Y691339D02*
X760591D01*
G01X742717Y665355D02*
Y691339D01*
G54D12*
G01X40683Y57570D02*
Y23939D01*
G01X42033Y57010D02*
Y23901D01*
G01Y57010D02*
Y23901D01*
G01X40683Y57570D02*
Y23939D01*
G01X42768Y59655D02*
X40683Y57570D01*
G01X44118Y59095D02*
X42033Y57010D01*
G01X42768Y67740D02*
Y59655D01*
G01X44118Y68300D02*
Y59095D01*
G01X41868Y68640D02*
X42768Y67740D01*
G01X43150Y69268D02*
X44118Y68300D01*
G01Y59095D02*
X42033Y57010D01*
G01X42768Y59655D02*
X40683Y57570D01*
G01X44118Y68300D02*
Y59095D01*
G01X42768Y67740D02*
Y59655D01*
G01X43150Y69268D02*
X44118Y68300D01*
G01X41868Y68640D02*
X42768Y67740D01*
G01X103656Y37362D02*
Y23920D01*
G01X105006Y37922D02*
Y23920D01*
G01X101770Y39248D02*
X103656Y37362D01*
G01X103120Y39808D02*
X105006Y37922D01*
G01X101770Y41468D02*
Y39248D01*
G01X103120Y40908D02*
Y39808D01*
G01X103110Y42808D02*
X101770Y41468D01*
G01X103670Y41458D02*
X103120Y40908D01*
G01X105552Y41458D02*
X103670D01*
G01X106892Y42798D02*
X105552Y41458D01*
G01X105006Y37922D02*
Y23920D01*
G01X103656Y37362D02*
Y23920D01*
G01X103120Y39808D02*
X105006Y37922D01*
G01X101770Y39248D02*
X103656Y37362D01*
G01X103120Y40908D02*
Y39808D01*
G01X101770Y41468D02*
Y39248D01*
G01X103670Y41458D02*
X103120Y40908D01*
G01X103110Y42808D02*
X101770Y41468D01*
G01X105552Y41458D02*
X103670D01*
G01X106892Y42798D02*
X105552Y41458D01*
G01X87908Y57558D02*
Y23920D01*
G01X89258Y57000D02*
Y23920D01*
G01Y57000D02*
Y23920D01*
G01X87908Y57558D02*
Y23920D01*
G01X72160Y57557D02*
Y23920D01*
G01X73510Y56997D02*
Y23920D01*
G01Y56997D02*
Y23920D01*
G01X72160Y57557D02*
Y23920D01*
G01X56412Y57722D02*
Y23920D01*
G01X57762Y51635D02*
Y23920D01*
G01Y51635D02*
Y23920D01*
G01X56412Y57722D02*
Y23920D01*
G01Y57722D02*
Y23920D01*
G01Y57722D02*
Y23920D01*
G01X104992Y42808D02*
X103110D01*
G01X105542Y43358D02*
X104992Y42808D01*
G01X105542Y44458D02*
Y43358D01*
G01X106892Y45018D02*
Y42798D01*
G01X104992Y45008D02*
X105542Y44458D01*
G01X105552Y46358D02*
X106892Y45018D01*
G01X103110Y45008D02*
X104992D01*
G01X103670Y46358D02*
X105552D01*
G01X101770Y46348D02*
X103110Y45008D01*
G01X103120Y46908D02*
X103670Y46358D01*
G01X101770Y48568D02*
Y46348D01*
G01X103120Y48008D02*
Y46908D01*
G01X103110Y49908D02*
X101770Y48568D01*
G01X103670Y48558D02*
X103120Y48008D01*
G01X104992Y49908D02*
X103110D01*
G01X105552Y48558D02*
X103670D01*
G01X105542Y50458D02*
X104992Y49908D01*
G01X106892Y49898D02*
X105552Y48558D01*
G01X105542Y51558D02*
Y50458D01*
G01X106892Y52118D02*
Y49898D01*
G01X104992Y52108D02*
X105542Y51558D01*
G01X105552Y53458D02*
X106892Y52118D01*
G01X103110Y52108D02*
X104992D01*
G01X103670Y53458D02*
X105552D01*
G01X101770Y53448D02*
X103110Y52108D01*
G01X103120Y54008D02*
X103670Y53458D01*
G01X101770Y55672D02*
Y53448D01*
G01X103120Y55112D02*
Y54008D01*
G01X105753Y59655D02*
X101770Y55672D01*
G01X107103Y59095D02*
X103120Y55112D01*
G01X105753Y67740D02*
Y59655D01*
G01X107103Y68300D02*
Y59095D01*
G01X104993Y68500D02*
X105753Y67740D01*
G01X106302Y69101D02*
X107103Y68300D01*
G01X104992Y42808D02*
X103110D01*
G01X105542Y43358D02*
X104992Y42808D01*
G01X106892Y45018D02*
Y42798D01*
G01X105542Y44458D02*
Y43358D01*
G01X105552Y46358D02*
X106892Y45018D01*
G01X104992Y45008D02*
X105542Y44458D01*
G01X103670Y46358D02*
X105552D01*
G01X103110Y45008D02*
X104992D01*
G01X103120Y46908D02*
X103670Y46358D01*
G01X101770Y46348D02*
X103110Y45008D01*
G01X103120Y48008D02*
Y46908D01*
G01X101770Y48568D02*
Y46348D01*
G01X103670Y48558D02*
X103120Y48008D01*
G01X103110Y49908D02*
X101770Y48568D01*
G01X105552Y48558D02*
X103670D01*
G01X104992Y49908D02*
X103110D01*
G01X106892Y49898D02*
X105552Y48558D01*
G01X105542Y50458D02*
X104992Y49908D01*
G01X106892Y52118D02*
Y49898D01*
G01X105542Y51558D02*
Y50458D01*
G01X105552Y53458D02*
X106892Y52118D01*
G01X104992Y52108D02*
X105542Y51558D01*
G01X103670Y53458D02*
X105552D01*
G01X103110Y52108D02*
X104992D01*
G01X103120Y54008D02*
X103670Y53458D01*
G01X101770Y53448D02*
X103110Y52108D01*
G01X103120Y55112D02*
Y54008D01*
G01X101770Y55672D02*
Y53448D01*
G01X107103Y59095D02*
X103120Y55112D01*
G01X105753Y59655D02*
X101770Y55672D01*
G01X107103Y68300D02*
Y59095D01*
G01X105753Y67740D02*
Y59655D01*
G01X106302Y69101D02*
X107103Y68300D01*
G01X104993Y68500D02*
X105753Y67740D01*
G01X90003Y59655D02*
X87907Y57559D01*
G01X91353Y59095D02*
X89258Y57000D01*
G01X90003Y67740D02*
Y59655D01*
G01X91353Y68300D02*
Y59095D01*
G01X89103Y68640D02*
X90003Y67740D01*
G01X90410Y69243D02*
X91353Y68300D01*
G01Y59095D02*
X89258Y57000D01*
G01X90003Y59655D02*
X87907Y57559D01*
G01X91353Y68300D02*
Y59095D01*
G01X90003Y67740D02*
Y59655D01*
G01X90410Y69243D02*
X91353Y68300D01*
G01X89103Y68640D02*
X90003Y67740D01*
G01X74258Y59655D02*
X72160Y57557D01*
G01X75608Y59095D02*
X73510Y56997D01*
G01X74258Y67740D02*
Y59655D01*
G01X75608Y68300D02*
Y59095D01*
G01X73388Y68610D02*
X74258Y67740D01*
G01X74600Y69308D02*
X75608Y68300D01*
G01Y59095D02*
X73510Y56997D01*
G01X74258Y59655D02*
X72160Y57557D01*
G01X75608Y68300D02*
Y59095D01*
G01X74258Y67740D02*
Y59655D01*
G01X74600Y69308D02*
X75608Y68300D01*
G01X73388Y68610D02*
X74258Y67740D01*
G01X57767Y51885D02*
Y51640D01*
G01X57762Y57162D02*
Y51890D01*
G01X58513Y59823D02*
X56412Y57722D01*
G01X59863Y59263D02*
X57762Y57162D01*
G01X58513Y67740D02*
Y59823D01*
G01X59863Y68300D02*
Y59263D01*
G01X57673Y68580D02*
X58513Y67740D01*
G01X59057Y69106D02*
X59863Y68300D01*
G01X57767Y51885D02*
Y51640D01*
G01X57762Y57162D02*
Y51890D01*
G01X59863Y59263D02*
X57762Y57162D01*
G01X58513Y59823D02*
X56412Y57722D01*
G01X59863Y68300D02*
Y59263D01*
G01X58513Y67740D02*
Y59823D01*
G01X59057Y69106D02*
X59863Y68300D01*
G01X57673Y68580D02*
X58513Y67740D01*
G01X167998Y57000D02*
Y23920D01*
G01X166648Y57558D02*
Y23920D01*
G01Y57558D02*
Y23920D01*
G01X167998Y57000D02*
Y23920D01*
G01X150900Y37397D02*
Y23920D01*
G01X152250Y37957D02*
Y23920D01*
G01X149050Y39247D02*
X150900Y37397D01*
G01X150400Y39807D02*
X152250Y37957D01*
G01X149050Y41467D02*
Y39247D01*
G01X150400Y40907D02*
Y39807D01*
G01X150390Y42807D02*
X149050Y41467D01*
G01X150950Y41457D02*
X150400Y40907D01*
G01X152850Y41457D02*
X150950D01*
G01X154140Y42747D02*
X152850Y41457D01*
G01X152250Y37957D02*
Y23920D01*
G01X150900Y37397D02*
Y23920D01*
G01X150400Y39807D02*
X152250Y37957D01*
G01X149050Y39247D02*
X150900Y37397D01*
G01X150400Y40907D02*
Y39807D01*
G01X149050Y41467D02*
Y39247D01*
G01X150950Y41457D02*
X150400Y40907D01*
G01X150390Y42807D02*
X149050Y41467D01*
G01X152850Y41457D02*
X150950D01*
G01X154140Y42747D02*
X152850Y41457D01*
G01X135152Y37387D02*
Y23920D01*
G01X136502Y37947D02*
Y23920D01*
G01X133290Y39249D02*
X135152Y37387D01*
G01X134640Y39809D02*
X136502Y37947D01*
G01X133290Y41469D02*
Y39249D01*
G01X134640Y40909D02*
Y39809D01*
G01X134630Y42809D02*
X133290Y41469D01*
G01X135190Y41459D02*
X134640Y40909D01*
G01X137024Y41459D02*
X135190D01*
G01X138364Y42799D02*
X137024Y41459D01*
G01X136502Y37947D02*
Y23920D01*
G01X135152Y37387D02*
Y23920D01*
G01X134640Y39809D02*
X136502Y37947D01*
G01X133290Y39249D02*
X135152Y37387D01*
G01X134640Y40909D02*
Y39809D01*
G01X133290Y41469D02*
Y39249D01*
G01X135190Y41459D02*
X134640Y40909D01*
G01X134630Y42809D02*
X133290Y41469D01*
G01X137024Y41459D02*
X135190D01*
G01X138364Y42799D02*
X137024Y41459D01*
G01X119404Y37372D02*
Y23920D01*
G01X120754Y37932D02*
Y23920D01*
G01X117530Y39246D02*
X119404Y37372D01*
G01X118880Y39806D02*
X120754Y37932D01*
G01X117530Y41466D02*
Y39246D01*
G01X118880Y40906D02*
Y39806D01*
G01X118870Y42806D02*
X117530Y41466D01*
G01X119430Y41456D02*
X118880Y40906D01*
G01X121288Y41456D02*
X119430D01*
G01X122628Y42796D02*
X121288Y41456D01*
G01X120754Y37932D02*
Y23920D01*
G01X119404Y37372D02*
Y23920D01*
G01X118880Y39806D02*
X120754Y37932D01*
G01X117530Y39246D02*
X119404Y37372D01*
G01X118880Y40906D02*
Y39806D01*
G01X117530Y41466D02*
Y39246D01*
G01X119430Y41456D02*
X118880Y40906D01*
G01X118870Y42806D02*
X117530Y41466D01*
G01X121288Y41456D02*
X119430D01*
G01X122628Y42796D02*
X121288Y41456D01*
G01X170093Y59095D02*
X167998Y57000D01*
G01X168743Y59655D02*
X166647Y57559D01*
G01X168743Y67740D02*
Y59655D01*
G01X169292Y69101D02*
X170093Y68300D01*
G01X167983Y68500D02*
X168743Y67740D01*
G01Y59655D02*
X166647Y57559D01*
G01X170093Y59095D02*
X167998Y57000D01*
G01X168743Y67740D02*
Y59655D01*
G01X167983Y68500D02*
X168743Y67740D01*
G01X169292Y69101D02*
X170093Y68300D01*
G01X152290Y42807D02*
X150390D01*
G01X152790Y43307D02*
X152290Y42807D01*
G01X152790Y44507D02*
Y43307D01*
G01X154140Y45067D02*
Y42747D01*
G01X152290Y45007D02*
X152790Y44507D01*
G01X152850Y46357D02*
X154140Y45067D01*
G01X150390Y45007D02*
X152290D01*
G01X150950Y46357D02*
X152850D01*
G01X149050Y46347D02*
X150390Y45007D01*
G01X150400Y46907D02*
X150950Y46357D01*
G01X149050Y48567D02*
Y46347D01*
G01X150400Y48007D02*
Y46907D01*
G01X150390Y49907D02*
X149050Y48567D01*
G01X150950Y48557D02*
X150400Y48007D01*
G01X152200Y49907D02*
X150390D01*
G01X152760Y48557D02*
X150950D01*
G01X152750Y50457D02*
X152200Y49907D01*
G01X154100Y49897D02*
X152760Y48557D01*
G01X152750Y51557D02*
Y50457D01*
G01X154100Y52117D02*
Y49897D01*
G01X152200Y52107D02*
X152750Y51557D01*
G01X152760Y53457D02*
X154100Y52117D01*
G01X150390Y52107D02*
X152200D01*
G01X150950Y53457D02*
X152760D01*
G01X149050Y53447D02*
X150390Y52107D01*
G01X150400Y54007D02*
X150950Y53457D01*
G01X149050Y55707D02*
Y53447D01*
G01X150400Y55147D02*
Y54007D01*
G01X152998Y59655D02*
X149050Y55707D01*
G01X154348Y59095D02*
X150400Y55147D01*
G01X152998Y67740D02*
Y59655D01*
G01X154348Y68300D02*
Y59095D01*
G01X152238Y68500D02*
X152998Y67740D01*
G01X153547Y69101D02*
X154348Y68300D01*
G01X152290Y42807D02*
X150390D01*
G01X152790Y43307D02*
X152290Y42807D01*
G01X154140Y45067D02*
Y42747D01*
G01X152790Y44507D02*
Y43307D01*
G01X152850Y46357D02*
X154140Y45067D01*
G01X152290Y45007D02*
X152790Y44507D01*
G01X150950Y46357D02*
X152850D01*
G01X150390Y45007D02*
X152290D01*
G01X150400Y46907D02*
X150950Y46357D01*
G01X149050Y46347D02*
X150390Y45007D01*
G01X150400Y48007D02*
Y46907D01*
G01X149050Y48567D02*
Y46347D01*
G01X150950Y48557D02*
X150400Y48007D01*
G01X150390Y49907D02*
X149050Y48567D01*
G01X152760Y48557D02*
X150950D01*
G01X152200Y49907D02*
X150390D01*
G01X154100Y49897D02*
X152760Y48557D01*
G01X152750Y50457D02*
X152200Y49907D01*
G01X154100Y52117D02*
Y49897D01*
G01X152750Y51557D02*
Y50457D01*
G01X152760Y53457D02*
X154100Y52117D01*
G01X152200Y52107D02*
X152750Y51557D01*
G01X150950Y53457D02*
X152760D01*
G01X150390Y52107D02*
X152200D01*
G01X150400Y54007D02*
X150950Y53457D01*
G01X149050Y53447D02*
X150390Y52107D01*
G01X150400Y55147D02*
Y54007D01*
G01X149050Y55707D02*
Y53447D01*
G01X154348Y59095D02*
X150400Y55147D01*
G01X152998Y59655D02*
X149050Y55707D01*
G01X154348Y68300D02*
Y59095D01*
G01X152998Y67740D02*
Y59655D01*
G01X153547Y69101D02*
X154348Y68300D01*
G01X152238Y68500D02*
X152998Y67740D01*
G01X136464Y42809D02*
X134630D01*
G01X137014Y43359D02*
X136464Y42809D01*
G01X137014Y44459D02*
Y43359D01*
G01X138364Y45019D02*
Y42799D01*
G01X136464Y45009D02*
X137014Y44459D01*
G01X137024Y46359D02*
X138364Y45019D01*
G01X134630Y45009D02*
X136464D01*
G01X135190Y46359D02*
X137024D01*
G01X133290Y46349D02*
X134630Y45009D01*
G01X134640Y46909D02*
X135190Y46359D01*
G01X133290Y48569D02*
Y46349D01*
G01X134640Y48009D02*
Y46909D01*
G01X134630Y49909D02*
X133290Y48569D01*
G01X135190Y48559D02*
X134640Y48009D01*
G01X136464Y49909D02*
X134630D01*
G01X137024Y48559D02*
X135190D01*
G01X137014Y50459D02*
X136464Y49909D01*
G01X138364Y49899D02*
X137024Y48559D01*
G01X137014Y51559D02*
Y50459D01*
G01X138364Y52119D02*
Y49899D01*
G01X136464Y52109D02*
X137014Y51559D01*
G01X137024Y53459D02*
X138364Y52119D01*
G01X134630Y52109D02*
X136464D01*
G01X135190Y53459D02*
X137024D01*
G01X133290Y53449D02*
X134630Y52109D01*
G01X134640Y54009D02*
X135190Y53459D01*
G01X133290Y55697D02*
Y53449D01*
G01X134640Y55137D02*
Y54009D01*
G01X137248Y59655D02*
X133290Y55697D01*
G01X138598Y59095D02*
X134640Y55137D01*
G01X137248Y67740D02*
Y59655D01*
G01X138598Y68300D02*
Y59095D01*
G01X136488Y68500D02*
X137248Y67740D01*
G01X137797Y69101D02*
X138598Y68300D01*
G01X136464Y42809D02*
X134630D01*
G01X137014Y43359D02*
X136464Y42809D01*
G01X138364Y45019D02*
Y42799D01*
G01X137014Y44459D02*
Y43359D01*
G01X137024Y46359D02*
X138364Y45019D01*
G01X136464Y45009D02*
X137014Y44459D01*
G01X135190Y46359D02*
X137024D01*
G01X134630Y45009D02*
X136464D01*
G01X134640Y46909D02*
X135190Y46359D01*
G01X133290Y46349D02*
X134630Y45009D01*
G01X134640Y48009D02*
Y46909D01*
G01X133290Y48569D02*
Y46349D01*
G01X135190Y48559D02*
X134640Y48009D01*
G01X134630Y49909D02*
X133290Y48569D01*
G01X137024Y48559D02*
X135190D01*
G01X136464Y49909D02*
X134630D01*
G01X138364Y49899D02*
X137024Y48559D01*
G01X137014Y50459D02*
X136464Y49909D01*
G01X138364Y52119D02*
Y49899D01*
G01X137014Y51559D02*
Y50459D01*
G01X137024Y53459D02*
X138364Y52119D01*
G01X136464Y52109D02*
X137014Y51559D01*
G01X135190Y53459D02*
X137024D01*
G01X134630Y52109D02*
X136464D01*
G01X134640Y54009D02*
X135190Y53459D01*
G01X133290Y53449D02*
X134630Y52109D01*
G01X134640Y55137D02*
Y54009D01*
G01X133290Y55697D02*
Y53449D01*
G01X138598Y59095D02*
X134640Y55137D01*
G01X137248Y59655D02*
X133290Y55697D01*
G01X138598Y68300D02*
Y59095D01*
G01X137248Y67740D02*
Y59655D01*
G01X137797Y69101D02*
X138598Y68300D01*
G01X136488Y68500D02*
X137248Y67740D01*
G01X120728Y42806D02*
X118870D01*
G01X121278Y43356D02*
X120728Y42806D01*
G01X121278Y44456D02*
Y43356D01*
G01X122628Y45016D02*
Y42796D01*
G01X120728Y45006D02*
X121278Y44456D01*
G01X121288Y46356D02*
X122628Y45016D01*
G01X118870Y45006D02*
X120728D01*
G01X119430Y46356D02*
X121288D01*
G01X117530Y46346D02*
X118870Y45006D01*
G01X118880Y46906D02*
X119430Y46356D01*
G01X117530Y48566D02*
Y46346D01*
G01X118880Y48006D02*
Y46906D01*
G01X118870Y49906D02*
X117530Y48566D01*
G01X119430Y48556D02*
X118880Y48006D01*
G01X120728Y49906D02*
X118870D01*
G01X121288Y48556D02*
X119430D01*
G01X121278Y50456D02*
X120728Y49906D01*
G01X122628Y49896D02*
X121288Y48556D01*
G01X121278Y51556D02*
Y50456D01*
G01X122628Y52116D02*
Y49896D01*
G01X120728Y52106D02*
X121278Y51556D01*
G01X121288Y53456D02*
X122628Y52116D01*
G01X118870Y52106D02*
X120728D01*
G01X119430Y53456D02*
X121288D01*
G01X117530Y53446D02*
X118870Y52106D01*
G01X118880Y54006D02*
X119430Y53456D01*
G01X117530Y55682D02*
Y53446D01*
G01X118880Y55122D02*
Y54006D01*
G01X121503Y59655D02*
X117530Y55682D01*
G01X122853Y59095D02*
X118880Y55122D01*
G01X121503Y67740D02*
Y59655D01*
G01X122853Y68300D02*
Y59095D01*
G01X120743Y68500D02*
X121503Y67740D01*
G01X122052Y69101D02*
X122853Y68300D01*
G01X120728Y42806D02*
X118870D01*
G01X121278Y43356D02*
X120728Y42806D01*
G01X122628Y45016D02*
Y42796D01*
G01X121278Y44456D02*
Y43356D01*
G01X121288Y46356D02*
X122628Y45016D01*
G01X120728Y45006D02*
X121278Y44456D01*
G01X119430Y46356D02*
X121288D01*
G01X118870Y45006D02*
X120728D01*
G01X118880Y46906D02*
X119430Y46356D01*
G01X117530Y46346D02*
X118870Y45006D01*
G01X118880Y48006D02*
Y46906D01*
G01X117530Y48566D02*
Y46346D01*
G01X119430Y48556D02*
X118880Y48006D01*
G01X118870Y49906D02*
X117530Y48566D01*
G01X121288Y48556D02*
X119430D01*
G01X120728Y49906D02*
X118870D01*
G01X122628Y49896D02*
X121288Y48556D01*
G01X121278Y50456D02*
X120728Y49906D01*
G01X122628Y52116D02*
Y49896D01*
G01X121278Y51556D02*
Y50456D01*
G01X121288Y53456D02*
X122628Y52116D01*
G01X120728Y52106D02*
X121278Y51556D01*
G01X119430Y53456D02*
X121288D01*
G01X118870Y52106D02*
X120728D01*
G01X118880Y54006D02*
X119430Y53456D01*
G01X117530Y53446D02*
X118870Y52106D01*
G01X118880Y55122D02*
Y54006D01*
G01X117530Y55682D02*
Y53446D01*
G01X122853Y59095D02*
X118880Y55122D01*
G01X121503Y59655D02*
X117530Y55682D01*
G01X122853Y68300D02*
Y59095D01*
G01X121503Y67740D02*
Y59655D01*
G01X122052Y69101D02*
X122853Y68300D01*
G01X120743Y68500D02*
X121503Y67740D01*
G01X229640Y38090D02*
Y23920D01*
G01X231280Y39730D02*
X229640Y38090D01*
G01X229340Y41380D02*
X230730D01*
G01X228000Y42720D02*
X229340Y41380D01*
G01X229640Y38090D02*
Y23920D01*
G01X231280Y39730D02*
X229640Y38090D01*
G01X229340Y41380D02*
X230730D01*
G01X228000Y42720D02*
X229340Y41380D01*
G01X213893Y61753D02*
Y23921D01*
G01X215243Y61193D02*
Y23919D01*
G01Y61193D02*
Y23919D01*
G01X213893Y61753D02*
Y23921D01*
G01X229900Y42730D02*
X231290D01*
G01X229350Y43280D02*
X229900Y42730D01*
G01X228000Y44940D02*
Y42720D01*
G01X229350Y44380D02*
Y43280D01*
G01X229340Y46280D02*
X228000Y44940D01*
G01X229900Y44930D02*
X229350Y44380D01*
G01X230730Y46280D02*
X229340D01*
G01X231290Y44930D02*
X229900D01*
G01X229340Y48480D02*
X230730D01*
G01X229900Y49830D02*
X231290D01*
G01X228000Y49820D02*
X229340Y48480D01*
G01X229350Y50380D02*
X229900Y49830D01*
G01X228000Y52040D02*
Y49820D01*
G01X229350Y51480D02*
Y50380D01*
G01X229340Y53380D02*
X228000Y52040D01*
G01X229900Y52030D02*
X229350Y51480D01*
G01X230730Y53380D02*
X229340D01*
G01X231290Y52030D02*
X229900D01*
G01X229340Y55580D02*
X230730D01*
G01X229900Y56930D02*
X231290D01*
G01X228000Y56920D02*
X229340Y55580D01*
G01X229350Y57480D02*
X229900Y56930D01*
G01X228000Y59390D02*
Y56920D01*
G01X229350Y58830D02*
Y57480D01*
G01X231738Y63128D02*
X228000Y59390D01*
G01X233088Y62568D02*
X229350Y58830D01*
G01X229900Y42730D02*
X231290D01*
G01X229350Y43280D02*
X229900Y42730D01*
G01X229350Y44380D02*
Y43280D01*
G01X228000Y44940D02*
Y42720D01*
G01X229900Y44930D02*
X229350Y44380D01*
G01X229340Y46280D02*
X228000Y44940D01*
G01X231290Y44930D02*
X229900D01*
G01X230730Y46280D02*
X229340D01*
G01X229900Y49830D02*
X231290D01*
G01X229340Y48480D02*
X230730D01*
G01X229350Y50380D02*
X229900Y49830D01*
G01X228000Y49820D02*
X229340Y48480D01*
G01X229350Y51480D02*
Y50380D01*
G01X228000Y52040D02*
Y49820D01*
G01X229900Y52030D02*
X229350Y51480D01*
G01X229340Y53380D02*
X228000Y52040D01*
G01X231290Y52030D02*
X229900D01*
G01X230730Y53380D02*
X229340D01*
G01X229900Y56930D02*
X231290D01*
G01X229340Y55580D02*
X230730D01*
G01X229350Y57480D02*
X229900Y56930D01*
G01X228000Y56920D02*
X229340Y55580D01*
G01X229350Y58830D02*
Y57480D01*
G01X228000Y59390D02*
Y56920D01*
G01X233088Y62568D02*
X229350Y58830D01*
G01X231738Y63128D02*
X228000Y59390D01*
G01X215988Y63848D02*
X213893Y61753D01*
G01X217338Y63288D02*
X215243Y61193D01*
G01X215988Y67740D02*
Y63848D01*
G01X217338Y68300D02*
Y63288D01*
G01X215168Y68560D02*
X215988Y67740D01*
G01X216537Y69101D02*
X217338Y68300D01*
G01Y63288D02*
X215243Y61193D01*
G01X215988Y63848D02*
X213893Y61753D01*
G01X217338Y68300D02*
Y63288D01*
G01X215988Y67740D02*
Y63848D01*
G01X216537Y69101D02*
X217338Y68300D01*
G01X215168Y68560D02*
X215988Y67740D01*
G01X170093Y68300D02*
Y59095D01*
G01Y68300D02*
Y59095D01*
G01X276883Y33537D02*
Y23920D01*
G01X278233Y32977D02*
Y23920D01*
G01X278203Y34857D02*
X276883Y33537D01*
G01X278763Y33507D02*
X278233Y32977D01*
G01X283180Y34857D02*
X278203D01*
G01X283740Y33507D02*
X278763D01*
G01X283730Y35407D02*
X283180Y34857D01*
G01X285080Y34847D02*
X283740Y33507D01*
G01X283730Y36507D02*
Y35407D01*
G01X285080Y37067D02*
Y34847D01*
G01X283180Y37057D02*
X283730Y36507D01*
G01X283740Y38407D02*
X285080Y37067D01*
G01X278203Y37057D02*
X283180D01*
G01X278763Y38407D02*
X283740D01*
G01X276883Y38377D02*
X278203Y37057D01*
G01X278233Y38937D02*
X278763Y38407D01*
G01X276883Y60790D02*
Y38377D01*
G01X278233Y60230D02*
Y38937D01*
G01Y32977D02*
Y23920D01*
G01X276883Y33537D02*
Y23920D01*
G01X278763Y33507D02*
X278233Y32977D01*
G01X278203Y34857D02*
X276883Y33537D01*
G01X283740Y33507D02*
X278763D01*
G01X283180Y34857D02*
X278203D01*
G01X285080Y34847D02*
X283740Y33507D01*
G01X283730Y35407D02*
X283180Y34857D01*
G01X285080Y37067D02*
Y34847D01*
G01X283730Y36507D02*
Y35407D01*
G01X283740Y38407D02*
X285080Y37067D01*
G01X283180Y37057D02*
X283730Y36507D01*
G01X278763Y38407D02*
X283740D01*
G01X278203Y37057D02*
X283180D01*
G01X278233Y38937D02*
X278763Y38407D01*
G01X276883Y38377D02*
X278203Y37057D01*
G01X278233Y60230D02*
Y38937D01*
G01X276883Y60790D02*
Y38377D01*
G01X290783Y28850D02*
X292632Y27001D01*
G01X290783Y34790D02*
Y28850D01*
G01X294273Y38280D02*
X290783Y34790D01*
G01Y28850D02*
X292632Y27001D01*
G01X290783Y34790D02*
Y28850D01*
G01X294273Y38280D02*
X290783Y34790D01*
G01X262250Y32093D02*
Y24155D01*
G01X260900Y31533D02*
Y24010D01*
G01X252433Y41910D02*
X262250Y32093D01*
G01X251083Y41350D02*
X260900Y31533D01*
G01X251083Y57973D02*
Y41350D01*
G01X260900Y31533D02*
Y24010D01*
G01X262250Y32093D02*
Y24155D01*
G01X251083Y41350D02*
X260900Y31533D01*
G01X252433Y41910D02*
X262250Y32093D01*
G01X251083Y57973D02*
Y41350D01*
G01X245388Y42817D02*
Y23920D01*
G01X246738Y42257D02*
Y23920D01*
G01Y42257D02*
Y23920D01*
G01X245388Y42817D02*
Y23920D01*
G01X230990Y37530D02*
Y23920D01*
G01X232630Y39170D02*
X230990Y37530D01*
G01X231280Y40830D02*
Y39730D01*
G01X232630Y41390D02*
Y39170D01*
G01X230730Y41380D02*
X231280Y40830D01*
G01X231290Y42730D02*
X232630Y41390D01*
G01X230990Y37530D02*
Y23920D01*
G01X232630Y39170D02*
X230990Y37530D01*
G01X232630Y41390D02*
Y39170D01*
G01X231280Y40830D02*
Y39730D01*
G01X231290Y42730D02*
X232630Y41390D01*
G01X230730Y41380D02*
X231280Y40830D01*
G01X279053Y62960D02*
X276883Y60790D01*
G01X280403Y62400D02*
X278233Y60230D01*
G01X279053Y68190D02*
Y62960D01*
G01X280403Y68750D02*
Y62400D01*
G01X278153Y69090D02*
X279053Y68190D01*
G01X278243Y70910D02*
X280403Y68750D01*
G01Y62400D02*
X278233Y60230D01*
G01X279053Y62960D02*
X276883Y60790D01*
G01X280403Y68750D02*
Y62400D01*
G01X279053Y68190D02*
Y62960D01*
G01X278243Y70910D02*
X280403Y68750D01*
G01X278153Y69090D02*
X279053Y68190D01*
G01X252433Y57413D02*
Y41910D01*
G01X255930Y60910D02*
X252433Y57413D01*
G01X255370Y62260D02*
X251083Y57973D01*
G01X261580Y60910D02*
X255930D01*
G01X261020Y62260D02*
X255370D01*
G01X264593Y63923D02*
X261580Y60910D01*
G01X263243Y64483D02*
X261020Y62260D01*
G01X264593Y68780D02*
Y63923D01*
G01X263243Y68220D02*
Y64483D01*
G01X262450Y70923D02*
X264593Y68780D01*
G01X262313Y69150D02*
X263243Y68220D01*
G01X252433Y57413D02*
Y41910D01*
G01X255370Y62260D02*
X251083Y57973D01*
G01X255930Y60910D02*
X252433Y57413D01*
G01X261020Y62260D02*
X255370D01*
G01X261580Y60910D02*
X255930D01*
G01X263243Y64483D02*
X261020Y62260D01*
G01X264593Y63923D02*
X261580Y60910D01*
G01X263243Y68220D02*
Y64483D01*
G01X264593Y68780D02*
Y63923D01*
G01X262313Y69150D02*
X263243Y68220D01*
G01X262450Y70923D02*
X264593Y68780D01*
G01X247676Y45105D02*
X245388Y42817D01*
G01X249026Y44545D02*
X246738Y42257D01*
G01X247676Y46205D02*
Y45105D01*
G01X249026Y46765D02*
Y44545D01*
G01X247126Y46755D02*
X247676Y46205D01*
G01X247686Y48105D02*
X249026Y46765D01*
G01X244530Y46755D02*
X247126D01*
G01X245090Y48105D02*
X247686D01*
G01X243240Y48045D02*
X244530Y46755D01*
G01X244590Y48605D02*
X245090Y48105D01*
G01X243240Y50365D02*
Y48045D01*
G01X244590Y49805D02*
Y48605D01*
G01X244530Y51655D02*
X243240Y50365D01*
G01X245090Y50305D02*
X244590Y49805D01*
G01X247126Y51655D02*
X244530D01*
G01X247686Y50305D02*
X245090D01*
G01X247676Y52205D02*
X247126Y51655D01*
G01X249026Y51645D02*
X247686Y50305D01*
G01X247676Y53305D02*
Y52205D01*
G01X249026Y53865D02*
Y51645D01*
G01X247126Y53855D02*
X247676Y53305D01*
G01X247686Y55205D02*
X249026Y53865D01*
G01X244440Y53855D02*
X247126D01*
G01X245000Y55205D02*
X247686D01*
G01X243100Y55195D02*
X244440Y53855D01*
G01X244450Y55755D02*
X245000Y55205D01*
G01X243100Y57415D02*
Y55195D01*
G01X244450Y56855D02*
Y55755D01*
G01X247440Y61755D02*
X243100Y57415D01*
G01X248790Y61195D02*
X244450Y56855D01*
G01X247440Y67783D02*
Y61755D01*
G01X248790Y68343D02*
Y61195D01*
G01X246723Y68500D02*
X247440Y67783D01*
G01X248032Y69101D02*
X248790Y68343D01*
G01X249026Y44545D02*
X246738Y42257D01*
G01X247676Y45105D02*
X245388Y42817D01*
G01X249026Y46765D02*
Y44545D01*
G01X247676Y46205D02*
Y45105D01*
G01X247686Y48105D02*
X249026Y46765D01*
G01X247126Y46755D02*
X247676Y46205D01*
G01X245090Y48105D02*
X247686D01*
G01X244530Y46755D02*
X247126D01*
G01X244590Y48605D02*
X245090Y48105D01*
G01X243240Y48045D02*
X244530Y46755D01*
G01X244590Y49805D02*
Y48605D01*
G01X243240Y50365D02*
Y48045D01*
G01X245090Y50305D02*
X244590Y49805D01*
G01X244530Y51655D02*
X243240Y50365D01*
G01X247686Y50305D02*
X245090D01*
G01X247126Y51655D02*
X244530D01*
G01X249026Y51645D02*
X247686Y50305D01*
G01X247676Y52205D02*
X247126Y51655D01*
G01X249026Y53865D02*
Y51645D01*
G01X247676Y53305D02*
Y52205D01*
G01X247686Y55205D02*
X249026Y53865D01*
G01X247126Y53855D02*
X247676Y53305D01*
G01X245000Y55205D02*
X247686D01*
G01X244440Y53855D02*
X247126D01*
G01X244450Y55755D02*
X245000Y55205D01*
G01X243100Y55195D02*
X244440Y53855D01*
G01X244450Y56855D02*
Y55755D01*
G01X243100Y57415D02*
Y55195D01*
G01X248790Y61195D02*
X244450Y56855D01*
G01X247440Y61755D02*
X243100Y57415D01*
G01X248790Y68343D02*
Y61195D01*
G01X247440Y67783D02*
Y61755D01*
G01X248032Y69101D02*
X248790Y68343D01*
G01X246723Y68500D02*
X247440Y67783D01*
G01X231280Y46830D02*
X230730Y46280D01*
G01X232630Y46270D02*
X231290Y44930D01*
G01X231280Y47930D02*
Y46830D01*
G01X232630Y48490D02*
Y46270D01*
G01X230730Y48480D02*
X231280Y47930D01*
G01X231290Y49830D02*
X232630Y48490D01*
G01X231280Y53930D02*
X230730Y53380D01*
G01X232630Y53370D02*
X231290Y52030D01*
G01X231280Y55030D02*
Y53930D01*
G01X232630Y55590D02*
Y53370D01*
G01X230730Y55580D02*
X231280Y55030D01*
G01X231290Y56930D02*
X232630Y55590D01*
G01X231738Y67740D02*
Y63128D01*
G01X233088Y68300D02*
Y62568D01*
G01X230978Y68500D02*
X231738Y67740D01*
G01X232282Y69106D02*
X233088Y68300D01*
G01X232630Y46270D02*
X231290Y44930D01*
G01X231280Y46830D02*
X230730Y46280D01*
G01X232630Y48490D02*
Y46270D01*
G01X231280Y47930D02*
Y46830D01*
G01X231290Y49830D02*
X232630Y48490D01*
G01X230730Y48480D02*
X231280Y47930D01*
G01X232630Y53370D02*
X231290Y52030D01*
G01X231280Y53930D02*
X230730Y53380D01*
G01X232630Y55590D02*
Y53370D01*
G01X231280Y55030D02*
Y53930D01*
G01X231290Y56930D02*
X232630Y55590D01*
G01X230730Y55580D02*
X231280Y55030D01*
G01X233088Y68300D02*
Y62568D01*
G01X231738Y67740D02*
Y63128D01*
G01X232282Y69106D02*
X233088Y68300D01*
G01X230978Y68500D02*
X231738Y67740D01*
G01X293982Y27561D02*
Y23920D01*
G01X292632Y27001D02*
Y23920D01*
G01X292133Y29410D02*
X293982Y27561D01*
G01X292133Y34230D02*
Y29410D01*
G01X294833Y36930D02*
X292133Y34230D01*
G01X301063Y36930D02*
X294833D01*
G01X300503Y38280D02*
X294273D01*
G01X303583Y39450D02*
X301063Y36930D01*
G01X302233Y40010D02*
X300503Y38280D01*
G01X303583Y68230D02*
Y39450D01*
G01X302233Y67670D02*
Y40010D01*
G01X292632Y27001D02*
Y23920D01*
G01X293982Y27561D02*
Y23920D01*
G01X292133Y29410D02*
X293982Y27561D01*
G01X292133Y34230D02*
Y29410D01*
G01X294833Y36930D02*
X292133Y34230D01*
G01X300503Y38280D02*
X294273D01*
G01X301063Y36930D02*
X294833D01*
G01X302233Y40010D02*
X300503Y38280D01*
G01X303583Y39450D02*
X301063Y36930D01*
G01X302233Y67670D02*
Y40010D01*
G01X303583Y68230D02*
Y39450D01*
G01X301963Y69850D02*
X303583Y68230D01*
G01X301403Y68500D02*
X302233Y67670D01*
G01X296533Y69850D02*
X301963D01*
G01X294286Y68500D02*
X301403D01*
G01D02*
X302233Y67670D01*
G01X301963Y69850D02*
X303583Y68230D01*
G01X294286Y68500D02*
X301403D01*
G01X296533Y69850D02*
X301963D01*
M02*
